(kicad_sch
	(version 20250114)
	(generator "eeschema")
	(generator_version "9.0")
	(paper "A3")
	(title_block
		(title "PolarFire SoM")
		(date "2025-07-22")
		(rev "1.1.4")
		(company "Antmicro Ltd")
		(comment 1 "www.antmicro.com")
	)
	(bus_alias "CPI"
		(members "D[0..9]" "HSYNC" "VSYNC" "PCLK")
	)
	(bus_alias "SPI"
		(members "MISO" "MOSI" "CLK" "CS")
	)
	(text "CrossLink"
		(exclude_from_sim no)
		(at 13.97 20.32 0)
		(effects
			(font
				(size 4 4)
				(thickness 0.8)
				(bold yes)
			)
			(justify left bottom)
		)
	)
	(text "Power filtering"
		(exclude_from_sim no)
		(at 275.59 87.63 0)
		(effects
			(font
				(size 4 4)
				(thickness 0.8)
				(bold yes)
			)
			(justify left bottom)
		)
	)
	(junction
		(at 153.67 190.5)
		(diameter 0)
		(color 0 0 0 0)
	)
	(junction
		(at 360.68 143.51)
		(diameter 0)
		(color 0 0 0 0)
	)
	(junction
		(at 260.35 118.11)
		(diameter 0)
		(color 0 0 0 0)
	)
	(junction
		(at 360.68 135.89)
		(diameter 0)
		(color 0 0 0 0)
	)
	(junction
		(at 81.28 83.82)
		(diameter 0)
		(color 0 0 0 0)
	)
	(junction
		(at 354.33 153.67)
		(diameter 0)
		(color 0 0 0 0)
	)
	(junction
		(at 260.35 107.95)
		(diameter 0)
		(color 0 0 0 0)
	)
	(junction
		(at 254 118.11)
		(diameter 0)
		(color 0 0 0 0)
	)
	(junction
		(at 303.53 135.89)
		(diameter 0)
		(color 0 0 0 0)
	)
	(junction
		(at 309.88 118.11)
		(diameter 0)
		(color 0 0 0 0)
	)
	(junction
		(at 303.53 100.33)
		(diameter 0)
		(color 0 0 0 0)
	)
	(junction
		(at 254 100.33)
		(diameter 0)
		(color 0 0 0 0)
	)
	(junction
		(at 360.68 118.11)
		(diameter 0)
		(color 0 0 0 0)
	)
	(junction
		(at 360.68 161.29)
		(diameter 0)
		(color 0 0 0 0)
	)
	(junction
		(at 360.68 153.67)
		(diameter 0)
		(color 0 0 0 0)
	)
	(junction
		(at 297.18 135.89)
		(diameter 0)
		(color 0 0 0 0)
	)
	(junction
		(at 260.35 125.73)
		(diameter 0)
		(color 0 0 0 0)
	)
	(junction
		(at 309.88 107.95)
		(diameter 0)
		(color 0 0 0 0)
	)
	(junction
		(at 360.68 100.33)
		(diameter 0)
		(color 0 0 0 0)
	)
	(junction
		(at 260.35 100.33)
		(diameter 0)
		(color 0 0 0 0)
	)
	(junction
		(at 360.68 107.95)
		(diameter 0)
		(color 0 0 0 0)
	)
	(junction
		(at 360.68 125.73)
		(diameter 0)
		(color 0 0 0 0)
	)
	(junction
		(at 313.69 135.89)
		(diameter 0)
		(color 0 0 0 0)
	)
	(junction
		(at 309.88 125.73)
		(diameter 0)
		(color 0 0 0 0)
	)
	(junction
		(at 354.33 100.33)
		(diameter 0)
		(color 0 0 0 0)
	)
	(junction
		(at 260.35 135.89)
		(diameter 0)
		(color 0 0 0 0)
	)
	(junction
		(at 303.53 143.51)
		(diameter 0)
		(color 0 0 0 0)
	)
	(junction
		(at 309.88 100.33)
		(diameter 0)
		(color 0 0 0 0)
	)
	(junction
		(at 303.53 118.11)
		(diameter 0)
		(color 0 0 0 0)
	)
	(junction
		(at 354.33 135.89)
		(diameter 0)
		(color 0 0 0 0)
	)
	(junction
		(at 153.67 187.96)
		(diameter 0)
		(color 0 0 0 0)
	)
	(junction
		(at 354.33 118.11)
		(diameter 0)
		(color 0 0 0 0)
	)
	(no_connect
		(at 86.36 154.94)
	)
	(no_connect
		(at 86.36 160.02)
	)
	(no_connect
		(at 86.36 111.76)
	)
	(no_connect
		(at 86.36 157.48)
	)
	(bus_entry
		(at 170.18 101.6)
		(size -2.54 2.54)
		(stroke
			(width 0)
			(type default)
		)
	)
	(bus_entry
		(at 170.18 111.76)
		(size -2.54 2.54)
		(stroke
			(width 0)
			(type default)
		)
	)
	(bus_entry
		(at 62.23 187.96)
		(size 2.54 2.54)
		(stroke
			(width 0)
			(type default)
		)
	)
	(bus_entry
		(at 59.69 88.9)
		(size -2.54 -2.54)
		(stroke
			(width 0)
			(type default)
		)
	)
	(bus_entry
		(at 62.23 139.7)
		(size 2.54 2.54)
		(stroke
			(width 0)
			(type default)
		)
	)
	(bus_entry
		(at 170.18 99.06)
		(size -2.54 2.54)
		(stroke
			(width 0)
			(type default)
		)
	)
	(bus_entry
		(at 170.18 144.78)
		(size -2.54 2.54)
		(stroke
			(width 0)
			(type default)
		)
	)
	(bus_entry
		(at 170.18 109.22)
		(size -2.54 2.54)
		(stroke
			(width 0)
			(type default)
		)
	)
	(bus_entry
		(at 62.23 177.8)
		(size 2.54 2.54)
		(stroke
			(width 0)
			(type default)
		)
	)
	(bus_entry
		(at 170.18 116.84)
		(size -2.54 2.54)
		(stroke
			(width 0)
			(type default)
		)
	)
	(bus_entry
		(at 62.23 119.38)
		(size 2.54 2.54)
		(stroke
			(width 0)
			(type default)
		)
	)
	(bus_entry
		(at 59.69 101.6)
		(size -2.54 -2.54)
		(stroke
			(width 0)
			(type default)
		)
	)
	(bus_entry
		(at 170.18 137.16)
		(size -2.54 2.54)
		(stroke
			(width 0)
			(type default)
		)
	)
	(bus_entry
		(at 62.23 134.62)
		(size 2.54 2.54)
		(stroke
			(width 0)
			(type default)
		)
	)
	(bus_entry
		(at 62.23 160.02)
		(size 2.54 2.54)
		(stroke
			(width 0)
			(type default)
		)
	)
	(bus_entry
		(at 59.69 99.06)
		(size -2.54 -2.54)
		(stroke
			(width 0)
			(type default)
		)
	)
	(bus_entry
		(at 170.18 134.62)
		(size -2.54 2.54)
		(stroke
			(width 0)
			(type default)
		)
	)
	(bus_entry
		(at 170.18 96.52)
		(size -2.54 2.54)
		(stroke
			(width 0)
			(type default)
		)
	)
	(bus_entry
		(at 62.23 149.86)
		(size 2.54 2.54)
		(stroke
			(width 0)
			(type default)
		)
	)
	(bus_entry
		(at 62.23 170.18)
		(size 2.54 2.54)
		(stroke
			(width 0)
			(type default)
		)
	)
	(bus_entry
		(at 62.23 124.46)
		(size 2.54 2.54)
		(stroke
			(width 0)
			(type default)
		)
	)
	(bus_entry
		(at 170.18 142.24)
		(size -2.54 2.54)
		(stroke
			(width 0)
			(type default)
		)
	)
	(bus_entry
		(at 62.23 111.76)
		(size 2.54 2.54)
		(stroke
			(width 0)
			(type default)
		)
	)
	(bus_entry
		(at 170.18 119.38)
		(size -2.54 2.54)
		(stroke
			(width 0)
			(type default)
		)
	)
	(bus_entry
		(at 62.23 106.68)
		(size 2.54 2.54)
		(stroke
			(width 0)
			(type default)
		)
	)
	(bus_entry
		(at 62.23 129.54)
		(size 2.54 2.54)
		(stroke
			(width 0)
			(type default)
		)
	)
	(bus_entry
		(at 170.18 106.68)
		(size -2.54 2.54)
		(stroke
			(width 0)
			(type default)
		)
	)
	(bus_entry
		(at 62.23 180.34)
		(size 2.54 2.54)
		(stroke
			(width 0)
			(type default)
		)
	)
	(bus_entry
		(at 62.23 172.72)
		(size 2.54 2.54)
		(stroke
			(width 0)
			(type default)
		)
	)
	(bus_entry
		(at 62.23 116.84)
		(size 2.54 2.54)
		(stroke
			(width 0)
			(type default)
		)
	)
	(bus_entry
		(at 170.18 114.3)
		(size -2.54 2.54)
		(stroke
			(width 0)
			(type default)
		)
	)
	(bus_entry
		(at 59.69 96.52)
		(size -2.54 -2.54)
		(stroke
			(width 0)
			(type default)
		)
	)
	(bus_entry
		(at 170.18 154.94)
		(size -2.54 2.54)
		(stroke
			(width 0)
			(type default)
		)
	)
	(bus_entry
		(at 62.23 167.64)
		(size 2.54 2.54)
		(stroke
			(width 0)
			(type default)
		)
	)
	(bus_entry
		(at 62.23 121.92)
		(size 2.54 2.54)
		(stroke
			(width 0)
			(type default)
		)
	)
	(bus_entry
		(at 62.23 175.26)
		(size 2.54 2.54)
		(stroke
			(width 0)
			(type default)
		)
	)
	(bus_entry
		(at 62.23 132.08)
		(size 2.54 2.54)
		(stroke
			(width 0)
			(type default)
		)
	)
	(bus_entry
		(at 170.18 152.4)
		(size -2.54 2.54)
		(stroke
			(width 0)
			(type default)
		)
	)
	(bus_entry
		(at 170.18 157.48)
		(size -2.54 2.54)
		(stroke
			(width 0)
			(type default)
		)
	)
	(bus_entry
		(at 62.23 162.56)
		(size 2.54 2.54)
		(stroke
			(width 0)
			(type default)
		)
	)
	(bus_entry
		(at 59.69 93.98)
		(size -2.54 -2.54)
		(stroke
			(width 0)
			(type default)
		)
	)
	(bus_entry
		(at 62.23 114.3)
		(size 2.54 2.54)
		(stroke
			(width 0)
			(type default)
		)
	)
	(bus_entry
		(at 62.23 165.1)
		(size 2.54 2.54)
		(stroke
			(width 0)
			(type default)
		)
	)
	(bus_entry
		(at 62.23 127)
		(size 2.54 2.54)
		(stroke
			(width 0)
			(type default)
		)
	)
	(bus_entry
		(at 62.23 185.42)
		(size 2.54 2.54)
		(stroke
			(width 0)
			(type default)
		)
	)
	(bus_entry
		(at 170.18 104.14)
		(size -2.54 2.54)
		(stroke
			(width 0)
			(type default)
		)
	)
	(bus_entry
		(at 59.69 91.44)
		(size -2.54 -2.54)
		(stroke
			(width 0)
			(type default)
		)
	)
	(bus_entry
		(at 62.23 182.88)
		(size 2.54 2.54)
		(stroke
			(width 0)
			(type default)
		)
	)
	(bus_entry
		(at 62.23 137.16)
		(size 2.54 2.54)
		(stroke
			(width 0)
			(type default)
		)
	)
	(bus_entry
		(at 170.18 147.32)
		(size -2.54 2.54)
		(stroke
			(width 0)
			(type default)
		)
	)
	(bus_entry
		(at 170.18 139.7)
		(size -2.54 2.54)
		(stroke
			(width 0)
			(type default)
		)
	)
	(bus_entry
		(at 170.18 149.86)
		(size -2.54 2.54)
		(stroke
			(width 0)
			(type default)
		)
	)
	(bus
		(pts
			(xy 170.18 95.25) (xy 171.45 93.98)
		)
		(stroke
			(width 0)
			(type default)
		)
	)
	(bus
		(pts
			(xy 59.69 104.14) (xy 60.96 104.14)
		)
		(stroke
			(width 0)
			(type default)
		)
	)
	(bus
		(pts
			(xy 62.23 134.62) (xy 62.23 137.16)
		)
		(stroke
			(width 0)
			(type default)
		)
	)
	(bus
		(pts
			(xy 62.23 121.92) (xy 62.23 124.46)
		)
		(stroke
			(width 0)
			(type default)
		)
	)
	(wire
		(pts
			(xy 260.35 107.95) (xy 260.35 109.22)
		)
		(stroke
			(width 0)
			(type default)
		)
	)
	(wire
		(pts
			(xy 254 107.95) (xy 260.35 107.95)
		)
		(stroke
			(width 0)
			(type default)
		)
	)
	(wire
		(pts
			(xy 254 119.38) (xy 254 118.11)
		)
		(stroke
			(width 0)
			(type default)
		)
	)
	(bus
		(pts
			(xy 170.18 133.35) (xy 170.18 134.62)
		)
		(stroke
			(width 0)
			(type default)
		)
	)
	(bus
		(pts
			(xy 170.18 147.32) (xy 170.18 149.86)
		)
		(stroke
			(width 0)
			(type default)
		)
	)
	(bus
		(pts
			(xy 62.23 182.88) (xy 62.23 185.42)
		)
		(stroke
			(width 0)
			(type default)
		)
	)
	(wire
		(pts
			(xy 81.28 86.36) (xy 86.36 86.36)
		)
		(stroke
			(width 0)
			(type default)
		)
	)
	(wire
		(pts
			(xy 149.86 127) (xy 168.91 127)
		)
		(stroke
			(width 0)
			(type default)
		)
	)
	(bus
		(pts
			(xy 62.23 111.76) (xy 62.23 114.3)
		)
		(stroke
			(width 0)
			(type default)
		)
	)
	(wire
		(pts
			(xy 335.28 135.89) (xy 339.09 135.89)
		)
		(stroke
			(width 0)
			(type default)
		)
	)
	(wire
		(pts
			(xy 149.86 157.48) (xy 167.64 157.48)
		)
		(stroke
			(width 0)
			(type default)
		)
	)
	(wire
		(pts
			(xy 335.28 153.67) (xy 339.09 153.67)
		)
		(stroke
			(width 0)
			(type default)
		)
	)
	(wire
		(pts
			(xy 68.58 83.82) (xy 72.39 83.82)
		)
		(stroke
			(width 0)
			(type default)
		)
	)
	(bus
		(pts
			(xy 62.23 167.64) (xy 62.23 170.18)
		)
		(stroke
			(width 0)
			(type default)
		)
	)
	(wire
		(pts
			(xy 297.18 143.51) (xy 303.53 143.51)
		)
		(stroke
			(width 0)
			(type default)
		)
	)
	(bus
		(pts
			(xy 170.18 149.86) (xy 170.18 152.4)
		)
		(stroke
			(width 0)
			(type default)
		)
	)
	(wire
		(pts
			(xy 59.69 91.44) (xy 86.36 91.44)
		)
		(stroke
			(width 0)
			(type default)
		)
	)
	(bus
		(pts
			(xy 57.15 96.52) (xy 57.15 99.06)
		)
		(stroke
			(width 0)
			(type default)
		)
	)
	(wire
		(pts
			(xy 64.77 137.16) (xy 86.36 137.16)
		)
		(stroke
			(width 0)
			(type default)
		)
	)
	(wire
		(pts
			(xy 303.53 118.11) (xy 309.88 118.11)
		)
		(stroke
			(width 0)
			(type default)
		)
	)
	(wire
		(pts
			(xy 344.17 118.11) (xy 354.33 118.11)
		)
		(stroke
			(width 0)
			(type default)
		)
	)
	(wire
		(pts
			(xy 81.28 73.66) (xy 81.28 83.82)
		)
		(stroke
			(width 0)
			(type default)
		)
	)
	(bus
		(pts
			(xy 62.23 177.8) (xy 62.23 180.34)
		)
		(stroke
			(width 0)
			(type default)
		)
	)
	(wire
		(pts
			(xy 149.86 142.24) (xy 167.64 142.24)
		)
		(stroke
			(width 0)
			(type default)
		)
	)
	(wire
		(pts
			(xy 360.68 161.29) (xy 360.68 160.02)
		)
		(stroke
			(width 0)
			(type default)
		)
	)
	(wire
		(pts
			(xy 354.33 153.67) (xy 360.68 153.67)
		)
		(stroke
			(width 0)
			(type default)
		)
	)
	(wire
		(pts
			(xy 71.12 105.41) (xy 81.28 105.41)
		)
		(stroke
			(width 0)
			(type default)
		)
	)
	(wire
		(pts
			(xy 153.67 187.96) (xy 153.67 190.5)
		)
		(stroke
			(width 0)
			(type default)
		)
	)
	(bus
		(pts
			(xy 57.15 93.98) (xy 57.15 96.52)
		)
		(stroke
			(width 0)
			(type default)
		)
	)
	(wire
		(pts
			(xy 149.86 109.22) (xy 167.64 109.22)
		)
		(stroke
			(width 0)
			(type default)
		)
	)
	(wire
		(pts
			(xy 81.28 104.14) (xy 86.36 104.14)
		)
		(stroke
			(width 0)
			(type default)
		)
	)
	(wire
		(pts
			(xy 311.15 118.11) (xy 309.88 118.11)
		)
		(stroke
			(width 0)
			(type default)
		)
	)
	(wire
		(pts
			(xy 360.68 125.73) (xy 360.68 124.46)
		)
		(stroke
			(width 0)
			(type default)
		)
	)
	(bus
		(pts
			(xy 57.15 86.36) (xy 57.15 88.9)
		)
		(stroke
			(width 0)
			(type default)
		)
	)
	(wire
		(pts
			(xy 303.53 107.95) (xy 309.88 107.95)
		)
		(stroke
			(width 0)
			(type default)
		)
	)
	(wire
		(pts
			(xy 309.88 125.73) (xy 309.88 127)
		)
		(stroke
			(width 0)
			(type default)
		)
	)
	(bus
		(pts
			(xy 62.23 165.1) (xy 62.23 167.64)
		)
		(stroke
			(width 0)
			(type default)
		)
	)
	(bus
		(pts
			(xy 62.23 185.42) (xy 62.23 187.96)
		)
		(stroke
			(width 0)
			(type default)
		)
	)
	(wire
		(pts
			(xy 240.03 135.89) (xy 260.35 135.89)
		)
		(stroke
			(width 0)
			(type default)
		)
	)
	(wire
		(pts
			(xy 64.77 162.56) (xy 86.36 162.56)
		)
		(stroke
			(width 0)
			(type default)
		)
	)
	(wire
		(pts
			(xy 260.35 100.33) (xy 261.62 100.33)
		)
		(stroke
			(width 0)
			(type default)
		)
	)
	(wire
		(pts
			(xy 64.77 167.64) (xy 86.36 167.64)
		)
		(stroke
			(width 0)
			(type default)
		)
	)
	(wire
		(pts
			(xy 335.28 118.11) (xy 339.09 118.11)
		)
		(stroke
			(width 0)
			(type default)
		)
	)
	(wire
		(pts
			(xy 149.86 83.82) (xy 163.83 83.82)
		)
		(stroke
			(width 0)
			(type default)
		)
	)
	(wire
		(pts
			(xy 254 107.95) (xy 254 106.68)
		)
		(stroke
			(width 0)
			(type default)
		)
	)
	(wire
		(pts
			(xy 59.69 101.6) (xy 86.36 101.6)
		)
		(stroke
			(width 0)
			(type default)
		)
	)
	(wire
		(pts
			(xy 313.69 135.89) (xy 314.96 135.89)
		)
		(stroke
			(width 0)
			(type default)
		)
	)
	(wire
		(pts
			(xy 149.86 152.4) (xy 167.64 152.4)
		)
		(stroke
			(width 0)
			(type default)
		)
	)
	(wire
		(pts
			(xy 260.35 125.73) (xy 260.35 127)
		)
		(stroke
			(width 0)
			(type default)
		)
	)
	(bus
		(pts
			(xy 54.61 88.9) (xy 55.88 88.9)
		)
		(stroke
			(width 0)
			(type default)
		)
	)
	(wire
		(pts
			(xy 297.18 137.16) (xy 297.18 135.89)
		)
		(stroke
			(width 0)
			(type default)
		)
	)
	(bus
		(pts
			(xy 54.61 83.82) (xy 55.88 83.82)
		)
		(stroke
			(width 0)
			(type default)
		)
	)
	(wire
		(pts
			(xy 361.95 153.67) (xy 360.68 153.67)
		)
		(stroke
			(width 0)
			(type default)
		)
	)
	(wire
		(pts
			(xy 354.33 119.38) (xy 354.33 118.11)
		)
		(stroke
			(width 0)
			(type default)
		)
	)
	(wire
		(pts
			(xy 153.67 185.42) (xy 153.67 187.96)
		)
		(stroke
			(width 0)
			(type default)
		)
	)
	(wire
		(pts
			(xy 303.53 143.51) (xy 313.69 143.51)
		)
		(stroke
			(width 0)
			(type default)
		)
	)
	(bus
		(pts
			(xy 62.23 172.72) (xy 62.23 175.26)
		)
		(stroke
			(width 0)
			(type default)
		)
	)
	(wire
		(pts
			(xy 354.33 125.73) (xy 360.68 125.73)
		)
		(stroke
			(width 0)
			(type default)
		)
	)
	(wire
		(pts
			(xy 354.33 143.51) (xy 354.33 142.24)
		)
		(stroke
			(width 0)
			(type default)
		)
	)
	(wire
		(pts
			(xy 149.86 185.42) (xy 153.67 185.42)
		)
		(stroke
			(width 0)
			(type default)
		)
	)
	(wire
		(pts
			(xy 64.77 134.62) (xy 86.36 134.62)
		)
		(stroke
			(width 0)
			(type default)
		)
	)
	(wire
		(pts
			(xy 303.53 143.51) (xy 303.53 144.78)
		)
		(stroke
			(width 0)
			(type default)
		)
	)
	(wire
		(pts
			(xy 149.86 116.84) (xy 167.64 116.84)
		)
		(stroke
			(width 0)
			(type default)
		)
	)
	(wire
		(pts
			(xy 344.17 135.89) (xy 354.33 135.89)
		)
		(stroke
			(width 0)
			(type default)
		)
	)
	(wire
		(pts
			(xy 172.72 124.46) (xy 149.86 124.46)
		)
		(stroke
			(width 0)
			(type default)
		)
	)
	(wire
		(pts
			(xy 71.12 194.31) (xy 81.28 194.31)
		)
		(stroke
			(width 0)
			(type default)
		)
	)
	(wire
		(pts
			(xy 360.68 143.51) (xy 360.68 142.24)
		)
		(stroke
			(width 0)
			(type default)
		)
	)
	(wire
		(pts
			(xy 260.35 142.24) (xy 260.35 143.51)
		)
		(stroke
			(width 0)
			(type default)
		)
	)
	(wire
		(pts
			(xy 149.86 104.14) (xy 167.64 104.14)
		)
		(stroke
			(width 0)
			(type default)
		)
	)
	(bus
		(pts
			(xy 170.18 154.94) (xy 170.18 157.48)
		)
		(stroke
			(width 0)
			(type default)
		)
	)
	(wire
		(pts
			(xy 81.28 193.04) (xy 86.36 193.04)
		)
		(stroke
			(width 0)
			(type default)
		)
	)
	(wire
		(pts
			(xy 149.86 88.9) (xy 163.83 88.9)
		)
		(stroke
			(width 0)
			(type default)
		)
	)
	(wire
		(pts
			(xy 309.88 101.6) (xy 309.88 100.33)
		)
		(stroke
			(width 0)
			(type default)
		)
	)
	(wire
		(pts
			(xy 254 101.6) (xy 254 100.33)
		)
		(stroke
			(width 0)
			(type default)
		)
	)
	(bus
		(pts
			(xy 62.23 106.68) (xy 62.23 111.76)
		)
		(stroke
			(width 0)
			(type default)
		)
	)
	(wire
		(pts
			(xy 149.86 111.76) (xy 167.64 111.76)
		)
		(stroke
			(width 0)
			(type default)
		)
	)
	(wire
		(pts
			(xy 149.86 160.02) (xy 167.64 160.02)
		)
		(stroke
			(width 0)
			(type default)
		)
	)
	(wire
		(pts
			(xy 354.33 161.29) (xy 360.68 161.29)
		)
		(stroke
			(width 0)
			(type default)
		)
	)
	(wire
		(pts
			(xy 81.28 105.41) (xy 81.28 104.14)
		)
		(stroke
			(width 0)
			(type default)
		)
	)
	(bus
		(pts
			(xy 62.23 129.54) (xy 62.23 132.08)
		)
		(stroke
			(width 0)
			(type default)
		)
	)
	(wire
		(pts
			(xy 153.67 190.5) (xy 153.67 191.77)
		)
		(stroke
			(width 0)
			(type default)
		)
	)
	(wire
		(pts
			(xy 290.83 135.89) (xy 297.18 135.89)
		)
		(stroke
			(width 0)
			(type default)
		)
	)
	(wire
		(pts
			(xy 64.77 139.7) (xy 86.36 139.7)
		)
		(stroke
			(width 0)
			(type default)
		)
	)
	(wire
		(pts
			(xy 260.35 100.33) (xy 260.35 101.6)
		)
		(stroke
			(width 0)
			(type default)
		)
	)
	(wire
		(pts
			(xy 254 125.73) (xy 254 124.46)
		)
		(stroke
			(width 0)
			(type default)
		)
	)
	(wire
		(pts
			(xy 344.17 153.67) (xy 354.33 153.67)
		)
		(stroke
			(width 0)
			(type default)
		)
	)
	(wire
		(pts
			(xy 354.33 100.33) (xy 360.68 100.33)
		)
		(stroke
			(width 0)
			(type default)
		)
	)
	(wire
		(pts
			(xy 297.18 143.51) (xy 297.18 142.24)
		)
		(stroke
			(width 0)
			(type default)
		)
	)
	(wire
		(pts
			(xy 260.35 135.89) (xy 260.35 137.16)
		)
		(stroke
			(width 0)
			(type default)
		)
	)
	(bus
		(pts
			(xy 170.18 95.25) (xy 170.18 96.52)
		)
		(stroke
			(width 0)
			(type default)
		)
	)
	(wire
		(pts
			(xy 354.33 125.73) (xy 354.33 124.46)
		)
		(stroke
			(width 0)
			(type default)
		)
	)
	(wire
		(pts
			(xy 354.33 135.89) (xy 360.68 135.89)
		)
		(stroke
			(width 0)
			(type default)
		)
	)
	(bus
		(pts
			(xy 170.18 139.7) (xy 170.18 142.24)
		)
		(stroke
			(width 0)
			(type default)
		)
	)
	(wire
		(pts
			(xy 303.53 135.89) (xy 303.53 137.16)
		)
		(stroke
			(width 0)
			(type default)
		)
	)
	(wire
		(pts
			(xy 361.95 135.89) (xy 360.68 135.89)
		)
		(stroke
			(width 0)
			(type default)
		)
	)
	(bus
		(pts
			(xy 62.23 132.08) (xy 62.23 134.62)
		)
		(stroke
			(width 0)
			(type default)
		)
	)
	(wire
		(pts
			(xy 354.33 143.51) (xy 360.68 143.51)
		)
		(stroke
			(width 0)
			(type default)
		)
	)
	(wire
		(pts
			(xy 64.77 180.34) (xy 86.36 180.34)
		)
		(stroke
			(width 0)
			(type default)
		)
	)
	(bus
		(pts
			(xy 170.18 106.68) (xy 170.18 109.22)
		)
		(stroke
			(width 0)
			(type default)
		)
	)
	(wire
		(pts
			(xy 303.53 101.6) (xy 303.53 100.33)
		)
		(stroke
			(width 0)
			(type default)
		)
	)
	(wire
		(pts
			(xy 261.62 118.11) (xy 260.35 118.11)
		)
		(stroke
			(width 0)
			(type default)
		)
	)
	(bus
		(pts
			(xy 62.23 162.56) (xy 62.23 165.1)
		)
		(stroke
			(width 0)
			(type default)
		)
	)
	(wire
		(pts
			(xy 354.33 137.16) (xy 354.33 135.89)
		)
		(stroke
			(width 0)
			(type default)
		)
	)
	(bus
		(pts
			(xy 62.23 127) (xy 62.23 129.54)
		)
		(stroke
			(width 0)
			(type default)
		)
	)
	(wire
		(pts
			(xy 149.86 114.3) (xy 167.64 114.3)
		)
		(stroke
			(width 0)
			(type default)
		)
	)
	(wire
		(pts
			(xy 281.94 135.89) (xy 285.75 135.89)
		)
		(stroke
			(width 0)
			(type default)
		)
	)
	(bus
		(pts
			(xy 62.23 175.26) (xy 62.23 177.8)
		)
		(stroke
			(width 0)
			(type default)
		)
	)
	(bus
		(pts
			(xy 62.23 170.18) (xy 62.23 172.72)
		)
		(stroke
			(width 0)
			(type default)
		)
	)
	(wire
		(pts
			(xy 64.77 165.1) (xy 86.36 165.1)
		)
		(stroke
			(width 0)
			(type default)
		)
	)
	(wire
		(pts
			(xy 354.33 101.6) (xy 354.33 100.33)
		)
		(stroke
			(width 0)
			(type default)
		)
	)
	(bus
		(pts
			(xy 55.88 83.82) (xy 57.15 85.09)
		)
		(stroke
			(width 0)
			(type default)
		)
	)
	(bus
		(pts
			(xy 55.88 88.9) (xy 57.15 90.17)
		)
		(stroke
			(width 0)
			(type default)
		)
	)
	(wire
		(pts
			(xy 311.15 100.33) (xy 309.88 100.33)
		)
		(stroke
			(width 0)
			(type default)
		)
	)
	(wire
		(pts
			(xy 64.77 121.92) (xy 86.36 121.92)
		)
		(stroke
			(width 0)
			(type default)
		)
	)
	(wire
		(pts
			(xy 149.86 154.94) (xy 167.64 154.94)
		)
		(stroke
			(width 0)
			(type default)
		)
	)
	(wire
		(pts
			(xy 254 118.11) (xy 260.35 118.11)
		)
		(stroke
			(width 0)
			(type default)
		)
	)
	(bus
		(pts
			(xy 62.23 119.38) (xy 62.23 121.92)
		)
		(stroke
			(width 0)
			(type default)
		)
	)
	(wire
		(pts
			(xy 303.53 125.73) (xy 309.88 125.73)
		)
		(stroke
			(width 0)
			(type default)
		)
	)
	(bus
		(pts
			(xy 62.23 137.16) (xy 62.23 139.7)
		)
		(stroke
			(width 0)
			(type default)
		)
	)
	(bus
		(pts
			(xy 60.96 147.32) (xy 62.23 148.59)
		)
		(stroke
			(width 0)
			(type default)
		)
	)
	(bus
		(pts
			(xy 57.15 85.09) (xy 57.15 86.36)
		)
		(stroke
			(width 0)
			(type default)
		)
	)
	(wire
		(pts
			(xy 64.77 116.84) (xy 86.36 116.84)
		)
		(stroke
			(width 0)
			(type default)
		)
	)
	(wire
		(pts
			(xy 360.68 143.51) (xy 360.68 144.78)
		)
		(stroke
			(width 0)
			(type default)
		)
	)
	(wire
		(pts
			(xy 234.95 100.33) (xy 242.57 100.33)
		)
		(stroke
			(width 0)
			(type default)
		)
	)
	(wire
		(pts
			(xy 309.88 125.73) (xy 309.88 124.46)
		)
		(stroke
			(width 0)
			(type default)
		)
	)
	(bus
		(pts
			(xy 62.23 124.46) (xy 62.23 127)
		)
		(stroke
			(width 0)
			(type default)
		)
	)
	(bus
		(pts
			(xy 170.18 109.22) (xy 170.18 111.76)
		)
		(stroke
			(width 0)
			(type default)
		)
	)
	(wire
		(pts
			(xy 309.88 118.11) (xy 309.88 119.38)
		)
		(stroke
			(width 0)
			(type default)
		)
	)
	(wire
		(pts
			(xy 149.86 167.64) (xy 168.91 167.64)
		)
		(stroke
			(width 0)
			(type default)
		)
	)
	(wire
		(pts
			(xy 59.69 93.98) (xy 86.36 93.98)
		)
		(stroke
			(width 0)
			(type default)
		)
	)
	(bus
		(pts
			(xy 170.18 114.3) (xy 170.18 116.84)
		)
		(stroke
			(width 0)
			(type default)
		)
	)
	(wire
		(pts
			(xy 149.86 139.7) (xy 167.64 139.7)
		)
		(stroke
			(width 0)
			(type default)
		)
	)
	(wire
		(pts
			(xy 149.86 187.96) (xy 153.67 187.96)
		)
		(stroke
			(width 0)
			(type default)
		)
	)
	(wire
		(pts
			(xy 172.72 163.83) (xy 172.72 162.56)
		)
		(stroke
			(width 0)
			(type default)
		)
	)
	(bus
		(pts
			(xy 170.18 142.24) (xy 170.18 144.78)
		)
		(stroke
			(width 0)
			(type default)
		)
	)
	(bus
		(pts
			(xy 59.69 147.32) (xy 60.96 147.32)
		)
		(stroke
			(width 0)
			(type default)
		)
	)
	(bus
		(pts
			(xy 170.18 116.84) (xy 170.18 119.38)
		)
		(stroke
			(width 0)
			(type default)
		)
	)
	(wire
		(pts
			(xy 361.95 100.33) (xy 360.68 100.33)
		)
		(stroke
			(width 0)
			(type default)
		)
	)
	(wire
		(pts
			(xy 149.86 121.92) (xy 167.64 121.92)
		)
		(stroke
			(width 0)
			(type default)
		)
	)
	(wire
		(pts
			(xy 149.86 165.1) (xy 168.91 165.1)
		)
		(stroke
			(width 0)
			(type default)
		)
	)
	(wire
		(pts
			(xy 64.77 190.5) (xy 86.36 190.5)
		)
		(stroke
			(width 0)
			(type default)
		)
	)
	(wire
		(pts
			(xy 64.77 182.88) (xy 86.36 182.88)
		)
		(stroke
			(width 0)
			(type default)
		)
	)
	(bus
		(pts
			(xy 62.23 114.3) (xy 62.23 116.84)
		)
		(stroke
			(width 0)
			(type default)
		)
	)
	(wire
		(pts
			(xy 360.68 118.11) (xy 360.68 119.38)
		)
		(stroke
			(width 0)
			(type default)
		)
	)
	(wire
		(pts
			(xy 354.33 107.95) (xy 360.68 107.95)
		)
		(stroke
			(width 0)
			(type default)
		)
	)
	(wire
		(pts
			(xy 149.86 147.32) (xy 167.64 147.32)
		)
		(stroke
			(width 0)
			(type default)
		)
	)
	(wire
		(pts
			(xy 64.77 185.42) (xy 86.36 185.42)
		)
		(stroke
			(width 0)
			(type default)
		)
	)
	(wire
		(pts
			(xy 247.65 100.33) (xy 254 100.33)
		)
		(stroke
			(width 0)
			(type default)
		)
	)
	(wire
		(pts
			(xy 64.77 124.46) (xy 86.36 124.46)
		)
		(stroke
			(width 0)
			(type default)
		)
	)
	(wire
		(pts
			(xy 64.77 152.4) (xy 86.36 152.4)
		)
		(stroke
			(width 0)
			(type default)
		)
	)
	(wire
		(pts
			(xy 260.35 107.95) (xy 260.35 106.68)
		)
		(stroke
			(width 0)
			(type default)
		)
	)
	(wire
		(pts
			(xy 64.77 175.26) (xy 86.36 175.26)
		)
		(stroke
			(width 0)
			(type default)
		)
	)
	(bus
		(pts
			(xy 170.18 134.62) (xy 170.18 137.16)
		)
		(stroke
			(width 0)
			(type default)
		)
	)
	(wire
		(pts
			(xy 149.86 137.16) (xy 167.64 137.16)
		)
		(stroke
			(width 0)
			(type default)
		)
	)
	(bus
		(pts
			(xy 170.18 96.52) (xy 170.18 99.06)
		)
		(stroke
			(width 0)
			(type default)
		)
	)
	(wire
		(pts
			(xy 59.69 96.52) (xy 86.36 96.52)
		)
		(stroke
			(width 0)
			(type default)
		)
	)
	(bus
		(pts
			(xy 62.23 180.34) (xy 62.23 182.88)
		)
		(stroke
			(width 0)
			(type default)
		)
	)
	(wire
		(pts
			(xy 303.53 135.89) (xy 313.69 135.89)
		)
		(stroke
			(width 0)
			(type default)
		)
	)
	(bus
		(pts
			(xy 170.18 152.4) (xy 170.18 154.94)
		)
		(stroke
			(width 0)
			(type default)
		)
	)
	(bus
		(pts
			(xy 170.18 133.35) (xy 171.45 132.08)
		)
		(stroke
			(width 0)
			(type default)
		)
	)
	(wire
		(pts
			(xy 280.67 118.11) (xy 285.75 118.11)
		)
		(stroke
			(width 0)
			(type default)
		)
	)
	(wire
		(pts
			(xy 149.86 144.78) (xy 167.64 144.78)
		)
		(stroke
			(width 0)
			(type default)
		)
	)
	(wire
		(pts
			(xy 290.83 118.11) (xy 303.53 118.11)
		)
		(stroke
			(width 0)
			(type default)
		)
	)
	(wire
		(pts
			(xy 309.88 107.95) (xy 309.88 106.68)
		)
		(stroke
			(width 0)
			(type default)
		)
	)
	(wire
		(pts
			(xy 149.86 99.06) (xy 167.64 99.06)
		)
		(stroke
			(width 0)
			(type default)
		)
	)
	(wire
		(pts
			(xy 86.36 83.82) (xy 81.28 83.82)
		)
		(stroke
			(width 0)
			(type default)
		)
	)
	(wire
		(pts
			(xy 149.86 149.86) (xy 167.64 149.86)
		)
		(stroke
			(width 0)
			(type default)
		)
	)
	(wire
		(pts
			(xy 64.77 177.8) (xy 86.36 177.8)
		)
		(stroke
			(width 0)
			(type default)
		)
	)
	(bus
		(pts
			(xy 172.72 132.08) (xy 171.45 132.08)
		)
		(stroke
			(width 0)
			(type default)
		)
	)
	(wire
		(pts
			(xy 309.88 107.95) (xy 309.88 109.22)
		)
		(stroke
			(width 0)
			(type default)
		)
	)
	(bus
		(pts
			(xy 170.18 144.78) (xy 170.18 147.32)
		)
		(stroke
			(width 0)
			(type default)
		)
	)
	(wire
		(pts
			(xy 59.69 88.9) (xy 86.36 88.9)
		)
		(stroke
			(width 0)
			(type default)
		)
	)
	(wire
		(pts
			(xy 360.68 107.95) (xy 360.68 109.22)
		)
		(stroke
			(width 0)
			(type default)
		)
	)
	(wire
		(pts
			(xy 81.28 194.31) (xy 81.28 193.04)
		)
		(stroke
			(width 0)
			(type default)
		)
	)
	(wire
		(pts
			(xy 354.33 107.95) (xy 354.33 106.68)
		)
		(stroke
			(width 0)
			(type default)
		)
	)
	(wire
		(pts
			(xy 64.77 172.72) (xy 86.36 172.72)
		)
		(stroke
			(width 0)
			(type default)
		)
	)
	(wire
		(pts
			(xy 64.77 170.18) (xy 86.36 170.18)
		)
		(stroke
			(width 0)
			(type default)
		)
	)
	(wire
		(pts
			(xy 303.53 107.95) (xy 303.53 106.68)
		)
		(stroke
			(width 0)
			(type default)
		)
	)
	(wire
		(pts
			(xy 360.68 100.33) (xy 360.68 101.6)
		)
		(stroke
			(width 0)
			(type default)
		)
	)
	(bus
		(pts
			(xy 57.15 90.17) (xy 57.15 91.44)
		)
		(stroke
			(width 0)
			(type default)
		)
	)
	(bus
		(pts
			(xy 170.18 111.76) (xy 170.18 114.3)
		)
		(stroke
			(width 0)
			(type default)
		)
	)
	(bus
		(pts
			(xy 62.23 160.02) (xy 62.23 162.56)
		)
		(stroke
			(width 0)
			(type default)
		)
	)
	(wire
		(pts
			(xy 254 100.33) (xy 260.35 100.33)
		)
		(stroke
			(width 0)
			(type default)
		)
	)
	(wire
		(pts
			(xy 149.86 101.6) (xy 167.64 101.6)
		)
		(stroke
			(width 0)
			(type default)
		)
	)
	(wire
		(pts
			(xy 354.33 161.29) (xy 354.33 160.02)
		)
		(stroke
			(width 0)
			(type default)
		)
	)
	(bus
		(pts
			(xy 57.15 91.44) (xy 57.15 93.98)
		)
		(stroke
			(width 0)
			(type default)
		)
	)
	(wire
		(pts
			(xy 344.17 100.33) (xy 354.33 100.33)
		)
		(stroke
			(width 0)
			(type default)
		)
	)
	(wire
		(pts
			(xy 64.77 132.08) (xy 86.36 132.08)
		)
		(stroke
			(width 0)
			(type default)
		)
	)
	(wire
		(pts
			(xy 238.76 118.11) (xy 242.57 118.11)
		)
		(stroke
			(width 0)
			(type default)
		)
	)
	(wire
		(pts
			(xy 64.77 129.54) (xy 86.36 129.54)
		)
		(stroke
			(width 0)
			(type default)
		)
	)
	(wire
		(pts
			(xy 260.35 125.73) (xy 260.35 124.46)
		)
		(stroke
			(width 0)
			(type default)
		)
	)
	(bus
		(pts
			(xy 62.23 148.59) (xy 62.23 149.86)
		)
		(stroke
			(width 0)
			(type default)
		)
	)
	(wire
		(pts
			(xy 149.86 106.68) (xy 167.64 106.68)
		)
		(stroke
			(width 0)
			(type default)
		)
	)
	(wire
		(pts
			(xy 64.77 109.22) (xy 86.36 109.22)
		)
		(stroke
			(width 0)
			(type default)
		)
	)
	(wire
		(pts
			(xy 360.68 153.67) (xy 360.68 154.94)
		)
		(stroke
			(width 0)
			(type default)
		)
	)
	(wire
		(pts
			(xy 361.95 118.11) (xy 360.68 118.11)
		)
		(stroke
			(width 0)
			(type default)
		)
	)
	(bus
		(pts
			(xy 62.23 116.84) (xy 62.23 119.38)
		)
		(stroke
			(width 0)
			(type default)
		)
	)
	(wire
		(pts
			(xy 303.53 143.51) (xy 303.53 142.24)
		)
		(stroke
			(width 0)
			(type default)
		)
	)
	(wire
		(pts
			(xy 64.77 114.3) (xy 86.36 114.3)
		)
		(stroke
			(width 0)
			(type default)
		)
	)
	(bus
		(pts
			(xy 62.23 105.41) (xy 62.23 106.68)
		)
		(stroke
			(width 0)
			(type default)
		)
	)
	(wire
		(pts
			(xy 303.53 100.33) (xy 309.88 100.33)
		)
		(stroke
			(width 0)
			(type default)
		)
	)
	(wire
		(pts
			(xy 81.28 83.82) (xy 77.47 83.82)
		)
		(stroke
			(width 0)
			(type default)
		)
	)
	(bus
		(pts
			(xy 62.23 149.86) (xy 62.23 160.02)
		)
		(stroke
			(width 0)
			(type default)
		)
	)
	(bus
		(pts
			(xy 170.18 137.16) (xy 170.18 139.7)
		)
		(stroke
			(width 0)
			(type default)
		)
	)
	(wire
		(pts
			(xy 360.68 161.29) (xy 360.68 162.56)
		)
		(stroke
			(width 0)
			(type default)
		)
	)
	(wire
		(pts
			(xy 247.65 118.11) (xy 254 118.11)
		)
		(stroke
			(width 0)
			(type default)
		)
	)
	(wire
		(pts
			(xy 360.68 125.73) (xy 360.68 127)
		)
		(stroke
			(width 0)
			(type default)
		)
	)
	(wire
		(pts
			(xy 64.77 142.24) (xy 86.36 142.24)
		)
		(stroke
			(width 0)
			(type default)
		)
	)
	(wire
		(pts
			(xy 64.77 187.96) (xy 86.36 187.96)
		)
		(stroke
			(width 0)
			(type default)
		)
	)
	(wire
		(pts
			(xy 360.68 135.89) (xy 360.68 137.16)
		)
		(stroke
			(width 0)
			(type default)
		)
	)
	(wire
		(pts
			(xy 354.33 118.11) (xy 360.68 118.11)
		)
		(stroke
			(width 0)
			(type default)
		)
	)
	(bus
		(pts
			(xy 171.45 93.98) (xy 172.72 93.98)
		)
		(stroke
			(width 0)
			(type default)
		)
	)
	(bus
		(pts
			(xy 60.96 104.14) (xy 62.23 105.41)
		)
		(stroke
			(width 0)
			(type default)
		)
	)
	(bus
		(pts
			(xy 170.18 104.14) (xy 170.18 106.68)
		)
		(stroke
			(width 0)
			(type default)
		)
	)
	(wire
		(pts
			(xy 71.12 144.78) (xy 86.36 144.78)
		)
		(stroke
			(width 0)
			(type default)
		)
	)
	(wire
		(pts
			(xy 360.68 107.95) (xy 360.68 106.68)
		)
		(stroke
			(width 0)
			(type default)
		)
	)
	(bus
		(pts
			(xy 170.18 101.6) (xy 170.18 104.14)
		)
		(stroke
			(width 0)
			(type default)
		)
	)
	(wire
		(pts
			(xy 313.69 142.24) (xy 313.69 143.51)
		)
		(stroke
			(width 0)
			(type default)
		)
	)
	(wire
		(pts
			(xy 297.18 135.89) (xy 303.53 135.89)
		)
		(stroke
			(width 0)
			(type default)
		)
	)
	(wire
		(pts
			(xy 149.86 129.54) (xy 168.91 129.54)
		)
		(stroke
			(width 0)
			(type default)
		)
	)
	(wire
		(pts
			(xy 234.95 99.06) (xy 234.95 100.33)
		)
		(stroke
			(width 0)
			(type default)
		)
	)
	(wire
		(pts
			(xy 260.35 118.11) (xy 260.35 119.38)
		)
		(stroke
			(width 0)
			(type default)
		)
	)
	(wire
		(pts
			(xy 64.77 127) (xy 86.36 127)
		)
		(stroke
			(width 0)
			(type default)
		)
	)
	(wire
		(pts
			(xy 149.86 119.38) (xy 167.64 119.38)
		)
		(stroke
			(width 0)
			(type default)
		)
	)
	(bus
		(pts
			(xy 170.18 99.06) (xy 170.18 101.6)
		)
		(stroke
			(width 0)
			(type default)
		)
	)
	(wire
		(pts
			(xy 335.28 100.33) (xy 339.09 100.33)
		)
		(stroke
			(width 0)
			(type default)
		)
	)
	(wire
		(pts
			(xy 172.72 162.56) (xy 149.86 162.56)
		)
		(stroke
			(width 0)
			(type default)
		)
	)
	(wire
		(pts
			(xy 303.53 119.38) (xy 303.53 118.11)
		)
		(stroke
			(width 0)
			(type default)
		)
	)
	(wire
		(pts
			(xy 149.86 190.5) (xy 153.67 190.5)
		)
		(stroke
			(width 0)
			(type default)
		)
	)
	(wire
		(pts
			(xy 64.77 119.38) (xy 86.36 119.38)
		)
		(stroke
			(width 0)
			(type default)
		)
	)
	(wire
		(pts
			(xy 59.69 99.06) (xy 86.36 99.06)
		)
		(stroke
			(width 0)
			(type default)
		)
	)
	(wire
		(pts
			(xy 290.83 100.33) (xy 303.53 100.33)
		)
		(stroke
			(width 0)
			(type default)
		)
	)
	(wire
		(pts
			(xy 313.69 137.16) (xy 313.69 135.89)
		)
		(stroke
			(width 0)
			(type default)
		)
	)
	(wire
		(pts
			(xy 303.53 125.73) (xy 303.53 124.46)
		)
		(stroke
			(width 0)
			(type default)
		)
	)
	(wire
		(pts
			(xy 149.86 93.98) (xy 163.83 93.98)
		)
		(stroke
			(width 0)
			(type default)
		)
	)
	(wire
		(pts
			(xy 280.67 100.33) (xy 285.75 100.33)
		)
		(stroke
			(width 0)
			(type default)
		)
	)
	(wire
		(pts
			(xy 254 125.73) (xy 260.35 125.73)
		)
		(stroke
			(width 0)
			(type default)
		)
	)
	(wire
		(pts
			(xy 172.72 125.73) (xy 172.72 124.46)
		)
		(stroke
			(width 0)
			(type default)
		)
	)
	(wire
		(pts
			(xy 354.33 154.94) (xy 354.33 153.67)
		)
		(stroke
			(width 0)
			(type default)
		)
	)
	(label "Crosslink_B2.D5"
		(at 65.405 180.34 0)
		(effects
			(font
				(size 1.27 1.27)
			)
			(justify left bottom)
		)
	)
	(label "Crosslink_B2.D0"
		(at 65.405 170.18 0)
		(effects
			(font
				(size 1.27 1.27)
			)
			(justify left bottom)
		)
	)
	(label "CAM1.D1_N"
		(at 165.735 111.76 180)
		(effects
			(font
				(size 1.27 1.27)
			)
			(justify right bottom)
		)
	)
	(label "CL_VCCAUX"
		(at 163.83 88.9 180)
		(effects
			(font
				(size 1.27 1.27)
			)
			(justify right bottom)
		)
	)
	(label "DSI1.D0_N"
		(at 165.735 144.78 180)
		(effects
			(font
				(size 1.27 1.27)
			)
			(justify right bottom)
		)
	)
	(label "CAM1.D2_N"
		(at 165.735 116.84 180)
		(effects
			(font
				(size 1.27 1.27)
			)
			(justify right bottom)
		)
	)
	(label "Crosslink_B2.VSYNC"
		(at 65.405 162.56 0)
		(effects
			(font
				(size 1.27 1.27)
			)
			(justify left bottom)
		)
	)
	(label "CL_VCCA_DPHY1"
		(at 168.91 165.1 180)
		(effects
			(font
				(size 1.27 1.27)
			)
			(justify right bottom)
		)
	)
	(label "CL_VCCA_DPHY0"
		(at 168.91 127 180)
		(effects
			(font
				(size 1.27 1.27)
			)
			(justify right bottom)
		)
	)
	(label "CAM1.D0_N"
		(at 165.735 106.68 180)
		(effects
			(font
				(size 1.27 1.27)
			)
			(justify right bottom)
		)
	)
	(label "Crosslink.CS"
		(at 59.69 96.52 0)
		(effects
			(font
				(size 1.27 1.27)
			)
			(justify left bottom)
		)
	)
	(label "Crosslink_B2.D8"
		(at 65.405 187.96 0)
		(effects
			(font
				(size 1.27 1.27)
			)
			(justify left bottom)
		)
	)
	(label "CL_VCC"
		(at 303.53 135.89 180)
		(effects
			(font
				(size 1.27 1.27)
			)
			(justify right bottom)
		)
	)
	(label "CL_VCCIO0"
		(at 71.12 105.41 0)
		(effects
			(font
				(size 1.27 1.27)
			)
			(justify left bottom)
		)
	)
	(label "CL_VCCA_DPHY0"
		(at 360.68 100.33 180)
		(effects
			(font
				(size 1.27 1.27)
			)
			(justify right bottom)
		)
	)
	(label "Crosslink_B2.PCLK"
		(at 65.405 167.64 0)
		(effects
			(font
				(size 1.27 1.27)
			)
			(justify left bottom)
		)
	)
	(label "Crosslink_B2.D7"
		(at 65.405 185.42 0)
		(effects
			(font
				(size 1.27 1.27)
			)
			(justify left bottom)
		)
	)
	(label "CL_VCCIO1"
		(at 71.12 144.78 0)
		(effects
			(font
				(size 1.27 1.27)
			)
			(justify left bottom)
		)
	)
	(label "Crosslink_B1.D8"
		(at 65.405 139.7 0)
		(effects
			(font
				(size 1.27 1.27)
			)
			(justify left bottom)
		)
	)
	(label "Crosslink_B1.D6"
		(at 65.405 134.62 0)
		(effects
			(font
				(size 1.27 1.27)
			)
			(justify left bottom)
		)
	)
	(label "Crosslink_B2.D6"
		(at 65.405 182.88 0)
		(effects
			(font
				(size 1.27 1.27)
			)
			(justify left bottom)
		)
	)
	(label "CL_VCCIO0"
		(at 260.35 100.33 180)
		(effects
			(font
				(size 1.27 1.27)
			)
			(justify right bottom)
		)
	)
	(label "Crosslink_B1.D3"
		(at 65.405 129.54 0)
		(effects
			(font
				(size 1.27 1.27)
			)
			(justify left bottom)
		)
	)
	(label "CL_VCCGPLL"
		(at 260.35 118.11 180)
		(effects
			(font
				(size 1.27 1.27)
			)
			(justify right bottom)
		)
	)
	(label "CAM1.C_P"
		(at 165.735 99.06 180)
		(effects
			(font
				(size 1.27 1.27)
			)
			(justify right bottom)
		)
	)
	(label "CL_VCCPLL_DPHY0"
		(at 168.91 129.54 180)
		(effects
			(font
				(size 1.27 1.27)
			)
			(justify right bottom)
		)
	)
	(label "Crosslink_B1.D0"
		(at 65.405 121.92 0)
		(effects
			(font
				(size 1.27 1.27)
			)
			(justify left bottom)
		)
	)
	(label "CL_VCCPLL_DPHY1"
		(at 168.91 167.64 180)
		(effects
			(font
				(size 1.27 1.27)
			)
			(justify right bottom)
		)
	)
	(label "CL_VCCPLL_DPHY0"
		(at 360.68 135.89 180)
		(effects
			(font
				(size 1.27 1.27)
			)
			(justify right bottom)
		)
	)
	(label "Crosslink.SDA"
		(at 59.69 91.44 0)
		(effects
			(font
				(size 1.27 1.27)
			)
			(justify left bottom)
		)
	)
	(label "DSI1.D2_N"
		(at 165.735 154.94 180)
		(effects
			(font
				(size 1.27 1.27)
			)
			(justify right bottom)
		)
	)
	(label "Crosslink_B2.HSYNC"
		(at 65.405 165.1 0)
		(effects
			(font
				(size 1.27 1.27)
			)
			(justify left bottom)
		)
	)
	(label "Crosslink_B2.D4"
		(at 65.405 152.4 0)
		(effects
			(font
				(size 1.27 1.27)
			)
			(justify left bottom)
		)
	)
	(label "Crosslink.MISO"
		(at 59.69 101.6 0)
		(effects
			(font
				(size 1.27 1.27)
			)
			(justify left bottom)
		)
	)
	(label "CAM1.C_N"
		(at 165.735 101.6 180)
		(effects
			(font
				(size 1.27 1.27)
			)
			(justify right bottom)
		)
	)
	(label "Crosslink_B1.D7"
		(at 65.405 137.16 0)
		(effects
			(font
				(size 1.27 1.27)
			)
			(justify left bottom)
		)
	)
	(label "CL_VCCPLL_DPHY1"
		(at 360.68 153.67 180)
		(effects
			(font
				(size 1.27 1.27)
			)
			(justify right bottom)
		)
	)
	(label "Crosslink_B2.D2"
		(at 65.405 175.26 0)
		(effects
			(font
				(size 1.27 1.27)
			)
			(justify left bottom)
		)
	)
	(label "CL_VCC"
		(at 163.83 83.82 180)
		(effects
			(font
				(size 1.27 1.27)
			)
			(justify right bottom)
		)
	)
	(label "DSI1.D3_N"
		(at 165.735 160.02 180)
		(effects
			(font
				(size 1.27 1.27)
			)
			(justify right bottom)
		)
	)
	(label "Crosslink_B2.D9"
		(at 65.405 190.5 0)
		(effects
			(font
				(size 1.27 1.27)
			)
			(justify left bottom)
		)
	)
	(label "DSI1.D1_N"
		(at 165.735 149.86 180)
		(effects
			(font
				(size 1.27 1.27)
			)
			(justify right bottom)
		)
	)
	(label "Crosslink.SCL"
		(at 59.69 88.9 0)
		(effects
			(font
				(size 1.27 1.27)
			)
			(justify left bottom)
		)
	)
	(label "DSI1.C_N"
		(at 165.735 139.7 180)
		(effects
			(font
				(size 1.27 1.27)
			)
			(justify right bottom)
		)
	)
	(label "Crosslink.MOSI"
		(at 59.69 93.98 0)
		(effects
			(font
				(size 1.27 1.27)
			)
			(justify left bottom)
		)
	)
	(label "Crosslink_B1.D9"
		(at 65.405 142.24 0)
		(effects
			(font
				(size 1.27 1.27)
			)
			(justify left bottom)
		)
	)
	(label "DSI1.D1_P"
		(at 165.735 147.32 180)
		(effects
			(font
				(size 1.27 1.27)
			)
			(justify right bottom)
		)
	)
	(label "DSI1.D2_P"
		(at 165.735 152.4 180)
		(effects
			(font
				(size 1.27 1.27)
			)
			(justify right bottom)
		)
	)
	(label "CL_VCCA_DPHY1"
		(at 360.68 118.11 180)
		(effects
			(font
				(size 1.27 1.27)
			)
			(justify right bottom)
		)
	)
	(label "DSI1.D0_P"
		(at 165.735 142.24 180)
		(effects
			(font
				(size 1.27 1.27)
			)
			(justify right bottom)
		)
	)
	(label "CL_VCCAUX"
		(at 260.35 135.89 180)
		(effects
			(font
				(size 1.27 1.27)
			)
			(justify right bottom)
		)
	)
	(label "CAM1.D2_P"
		(at 165.735 114.3 180)
		(effects
			(font
				(size 1.27 1.27)
			)
			(justify right bottom)
		)
	)
	(label "CAM1.D3_N"
		(at 165.735 121.92 180)
		(effects
			(font
				(size 1.27 1.27)
			)
			(justify right bottom)
		)
	)
	(label "Crosslink_B1.D2"
		(at 65.405 127 0)
		(effects
			(font
				(size 1.27 1.27)
			)
			(justify left bottom)
		)
	)
	(label "CAM1.D0_P"
		(at 165.735 104.14 180)
		(effects
			(font
				(size 1.27 1.27)
			)
			(justify right bottom)
		)
	)
	(label "CL_VCCIO2"
		(at 303.53 100.33 180)
		(effects
			(font
				(size 1.27 1.27)
			)
			(justify right bottom)
		)
	)
	(label "DSI1.D3_P"
		(at 165.735 157.48 180)
		(effects
			(font
				(size 1.27 1.27)
			)
			(justify right bottom)
		)
	)
	(label "Crosslink_B1.D1"
		(at 65.405 124.46 0)
		(effects
			(font
				(size 1.27 1.27)
			)
			(justify left bottom)
		)
	)
	(label "CL_VCCIO2"
		(at 71.12 194.31 0)
		(effects
			(font
				(size 1.27 1.27)
			)
			(justify left bottom)
		)
	)
	(label "Crosslink.CLK"
		(at 59.69 99.06 0)
		(effects
			(font
				(size 1.27 1.27)
			)
			(justify left bottom)
		)
	)
	(label "Crosslink_B1.D4"
		(at 65.405 109.22 0)
		(effects
			(font
				(size 1.27 1.27)
			)
			(justify left bottom)
		)
	)
	(label "CL_VCCGPLL"
		(at 163.83 93.98 180)
		(effects
			(font
				(size 1.27 1.27)
			)
			(justify right bottom)
		)
	)
	(label "Crosslink_B1.HSYNC"
		(at 65.405 116.84 0)
		(effects
			(font
				(size 1.27 1.27)
			)
			(justify left bottom)
		)
	)
	(label "Crosslink_B1.VSYNC"
		(at 65.405 114.3 0)
		(effects
			(font
				(size 1.27 1.27)
			)
			(justify left bottom)
		)
	)
	(label "Crosslink_B1.D5"
		(at 65.405 132.08 0)
		(effects
			(font
				(size 1.27 1.27)
			)
			(justify left bottom)
		)
	)
	(label "Crosslink_B2.D1"
		(at 65.405 172.72 0)
		(effects
			(font
				(size 1.27 1.27)
			)
			(justify left bottom)
		)
	)
	(label "DSI1.C_P"
		(at 165.735 137.16 180)
		(effects
			(font
				(size 1.27 1.27)
			)
			(justify right bottom)
		)
	)
	(label "Crosslink_B1.PCLK"
		(at 65.405 119.38 0)
		(effects
			(font
				(size 1.27 1.27)
			)
			(justify left bottom)
		)
	)
	(label "CAM1.D3_P"
		(at 165.735 119.38 180)
		(effects
			(font
				(size 1.27 1.27)
			)
			(justify right bottom)
		)
	)
	(label "Crosslink_B2.D3"
		(at 65.405 177.8 0)
		(effects
			(font
				(size 1.27 1.27)
			)
			(justify left bottom)
		)
	)
	(label "CAM1.D1_P"
		(at 165.735 109.22 180)
		(effects
			(font
				(size 1.27 1.27)
			)
			(justify right bottom)
		)
	)
	(label "CL_VCCIO1"
		(at 303.53 118.11 180)
		(effects
			(font
				(size 1.27 1.27)
			)
			(justify right bottom)
		)
	)
	(global_label "1V8_CL"
		(shape input)
		(at 280.67 100.33 180)
		(fields_autoplaced yes)
		(effects
			(font
				(size 1.27 1.27)
			)
			(justify right)
		)
		(property "Intersheetrefs" "${INTERSHEET_REFS}"
			(at 270.9115 100.33 0)
			(effects
				(font
					(size 1.27 1.27)
				)
				(justify right)
			)
		)
	)
	(global_label "2V5_CL"
		(shape input)
		(at 240.03 135.89 180)
		(fields_autoplaced yes)
		(effects
			(font
				(size 1.27 1.27)
			)
			(justify right)
		)
		(property "Intersheetrefs" "${INTERSHEET_REFS}"
			(at 230.2715 135.89 0)
			(effects
				(font
					(size 1.27 1.27)
				)
				(justify right)
			)
		)
	)
	(global_label "~{Crosslink_RESET}"
		(shape input)
		(at 81.28 73.66 180)
		(fields_autoplaced yes)
		(effects
			(font
				(size 1.27 1.27)
			)
			(justify right)
		)
		(property "Intersheetrefs" "${INTERSHEET_REFS}"
			(at 62.8736 73.66 0)
			(effects
				(font
					(size 1.27 1.27)
				)
				(justify right)
			)
		)
	)
	(global_label "1V8_CL"
		(shape input)
		(at 280.67 118.11 180)
		(fields_autoplaced yes)
		(effects
			(font
				(size 1.27 1.27)
			)
			(justify right)
		)
		(property "Intersheetrefs" "${INTERSHEET_REFS}"
			(at 270.9115 118.11 0)
			(effects
				(font
					(size 1.27 1.27)
				)
				(justify right)
			)
		)
	)
	(hierarchical_label "Crosslink_B1{CPI}"
		(shape input)
		(at 59.69 104.14 180)
		(effects
			(font
				(size 1.27 1.27)
			)
			(justify right)
		)
	)
	(hierarchical_label "Crosslink{SPI}"
		(shape bidirectional)
		(at 54.61 88.9 180)
		(effects
			(font
				(size 1.27 1.27)
			)
			(justify right)
		)
	)
	(hierarchical_label "DSI1{DSI}"
		(shape bidirectional)
		(at 172.72 132.08 0)
		(effects
			(font
				(size 1.27 1.27)
			)
			(justify left)
		)
	)
	(hierarchical_label "Crosslink_B2{CPI}"
		(shape input)
		(at 59.69 147.32 180)
		(effects
			(font
				(size 1.27 1.27)
			)
			(justify right)
		)
	)
	(hierarchical_label "CAM1{CSI}"
		(shape bidirectional)
		(at 172.72 93.98 0)
		(effects
			(font
				(size 1.27 1.27)
			)
			(justify left)
		)
	)
	(hierarchical_label "Crosslink{I^{2}C}"
		(shape bidirectional)
		(at 54.61 83.82 180)
		(effects
			(font
				(size 1.27 1.27)
			)
			(justify right)
		)
	)
	(symbol
		(lib_id "antmicropower:GND")
		(at 360.68 127 0)
		(unit 1)
		(exclude_from_sim no)
		(in_bom yes)
		(on_board yes)
		(dnp no)
		(property "Reference" "#PWR0198"
			(at 369.57 129.54 0)
			(effects
				(font
					(size 1.27 1.27)
					(thickness 0.15)
				)
				(justify left bottom)
				(hide yes)
			)
		)
		(property "Value" "GND"
			(at 360.68 130.81 0)
			(effects
				(font
					(size 1.27 1.27)
					(thickness 0.15)
				)
			)
		)
		(property "Footprint" ""
			(at 369.57 134.62 0)
			(effects
				(font
					(size 1.27 1.27)
					(thickness 0.15)
				)
				(justify left bottom)
				(hide yes)
			)
		)
		(property "Datasheet" ""
			(at 369.57 139.7 0)
			(effects
				(font
					(size 1.27 1.27)
					(thickness 0.15)
				)
				(justify left bottom)
				(hide yes)
			)
		)
		(property "Description" ""
			(at 360.68 127 0)
			(effects
				(font
					(size 1.27 1.27)
				)
				(hide yes)
			)
		)
		(property "Author" "Antmicro"
			(at 369.57 134.62 0)
			(effects
				(font
					(size 1.27 1.27)
					(thickness 0.15)
				)
				(justify left bottom)
				(hide yes)
			)
		)
		(property "License" "Apache-2.0"
			(at 369.57 137.16 0)
			(effects
				(font
					(size 1.27 1.27)
					(thickness 0.15)
				)
				(justify left bottom)
				(hide yes)
			)
		)
		(pin "1"
		)
		(instances
			(project "polarfire-som"
				(path ""
					(reference "#PWR0198")
					(unit 1)
				)
			)
		)
	)
	(symbol
		(lib_id "antmicropower:GND")
		(at 309.88 109.22 0)
		(unit 1)
		(exclude_from_sim no)
		(in_bom yes)
		(on_board yes)
		(dnp no)
		(property "Reference" "#PWR0190"
			(at 318.77 111.76 0)
			(effects
				(font
					(size 1.27 1.27)
					(thickness 0.15)
				)
				(justify left bottom)
				(hide yes)
			)
		)
		(property "Value" "GND"
			(at 309.88 113.03 0)
			(effects
				(font
					(size 1.27 1.27)
					(thickness 0.15)
				)
			)
		)
		(property "Footprint" ""
			(at 318.77 116.84 0)
			(effects
				(font
					(size 1.27 1.27)
					(thickness 0.15)
				)
				(justify left bottom)
				(hide yes)
			)
		)
		(property "Datasheet" ""
			(at 318.77 121.92 0)
			(effects
				(font
					(size 1.27 1.27)
					(thickness 0.15)
				)
				(justify left bottom)
				(hide yes)
			)
		)
		(property "Description" ""
			(at 309.88 109.22 0)
			(effects
				(font
					(size 1.27 1.27)
				)
				(hide yes)
			)
		)
		(property "Author" "Antmicro"
			(at 318.77 116.84 0)
			(effects
				(font
					(size 1.27 1.27)
					(thickness 0.15)
				)
				(justify left bottom)
				(hide yes)
			)
		)
		(property "License" "Apache-2.0"
			(at 318.77 119.38 0)
			(effects
				(font
					(size 1.27 1.27)
					(thickness 0.15)
				)
				(justify left bottom)
				(hide yes)
			)
		)
		(pin "1"
		)
		(instances
			(project "polarfire-som"
				(path ""
					(reference "#PWR0190")
					(unit 1)
				)
			)
		)
	)
	(symbol
		(lib_id "antmicroFerriteBeadsandChips:FB_120Z_1.2A_TDK-MPZ_0402")
		(at 344.17 100.33 180)
		(unit 1)
		(exclude_from_sim no)
		(in_bom yes)
		(on_board yes)
		(dnp no)
		(fields_autoplaced yes)
		(property "Reference" "FB7"
			(at 341.6681 93.98 0)
			(effects
				(font
					(size 1.27 1.27)
					(thickness 0.15)
				)
			)
		)
		(property "Value" "FB_120Z_1.2A_TDK-MPZ_0402"
			(at 330.2 97.79 0)
			(effects
				(font
					(size 1.27 1.27)
					(thickness 0.15)
				)
				(justify left bottom)
				(hide yes)
			)
		)
		(property "Footprint" "antmicro-footprints:FB_0402_1005Metric"
			(at 330.2 92.71 0)
			(effects
				(font
					(size 1.27 1.27)
					(thickness 0.15)
				)
				(justify left bottom)
				(hide yes)
			)
		)
		(property "Datasheet" "https://product.tdk.com/en/search/emc/emc/beads/info?part_no=MPZ1005S121CT000"
			(at 330.2 90.17 0)
			(effects
				(font
					(size 1.27 1.27)
					(thickness 0.15)
				)
				(justify left bottom)
				(hide yes)
			)
		)
		(property "Description" "Ferrite Bead, 0402 [1005 Metric], 120 ohm, 1.2A, MPZ, 0.06 ohm, ± 25%, DC Power line"
			(at 344.17 100.33 0)
			(effects
				(font
					(size 1.27 1.27)
				)
				(hide yes)
			)
		)
		(property "Val" "120Z/1.2A"
			(at 341.6681 96.52 0)
			(effects
				(font
					(size 1.27 1.27)
				)
			)
		)
		(property "MPN" "MPZ1005S121CT000"
			(at 330.2 87.63 0)
			(effects
				(font
					(size 1.27 1.27)
					(thickness 0.15)
				)
				(justify left bottom)
				(hide yes)
			)
		)
		(property "Manufacturer" "TDK"
			(at 330.2 85.09 0)
			(effects
				(font
					(size 1.27 1.27)
					(thickness 0.15)
				)
				(justify left bottom)
				(hide yes)
			)
		)
		(property "Current" ""
			(at 323.85 77.47 0)
			(effects
				(font
					(size 1.27 1.27)
					(thickness 0.15)
				)
				(justify left bottom)
				(hide yes)
			)
		)
		(property "Author" "Antmicro"
			(at 330.2 82.55 0)
			(effects
				(font
					(size 1.27 1.27)
					(thickness 0.15)
				)
				(justify left bottom)
				(hide yes)
			)
		)
		(property "License" "Apache-2.0"
			(at 330.2 80.01 0)
			(effects
				(font
					(size 1.27 1.27)
					(thickness 0.15)
				)
				(justify left bottom)
				(hide yes)
			)
		)
		(property "Public" ""
			(at 323.85 85.09 0)
			(effects
				(font
					(size 1.27 1.27)
				)
				(justify left bottom)
				(hide yes)
			)
		)
		(pin "1"
		)
		(pin "2"
		)
		(instances
			(project "polarfire-som"
				(path ""
					(reference "FB7")
					(unit 1)
				)
			)
		)
	)
	(symbol
		(lib_id "antmicroCapacitors0402:C_100n_0402")
		(at 309.88 124.46 90)
		(unit 1)
		(exclude_from_sim no)
		(in_bom yes)
		(on_board yes)
		(dnp no)
		(fields_autoplaced yes)
		(property "Reference" "C206"
			(at 312.42 120.6436 90)
			(effects
				(font
					(size 1.27 1.27)
					(thickness 0.15)
				)
				(justify right)
			)
		)
		(property "Value" "C_100n_0402"
			(at 320.04 104.14 0)
			(effects
				(font
					(size 1.27 1.27)
					(thickness 0.15)
				)
				(justify left bottom)
				(hide yes)
			)
		)
		(property "Footprint" "antmicro-footprints:C_0402_1005Metric"
			(at 322.58 104.14 0)
			(effects
				(font
					(size 1.27 1.27)
					(thickness 0.15)
				)
				(justify left bottom)
				(hide yes)
			)
		)
		(property "Datasheet" "https://www.murata.com/products/productdetail?partno=GRM155R61H104KE14%23"
			(at 325.12 104.14 0)
			(effects
				(font
					(size 1.27 1.27)
					(thickness 0.15)
				)
				(justify left bottom)
				(hide yes)
			)
		)
		(property "Description" "SMD Multilayer Ceramic Capacitor, 0.1 µF, 50 V, 0402 [1005 Metric], ± 10%, X5R, GRM Series"
			(at 309.88 124.46 0)
			(effects
				(font
					(size 1.27 1.27)
				)
				(hide yes)
			)
		)
		(property "MPN" "GRM155R61H104KE14D"
			(at 327.66 104.14 0)
			(effects
				(font
					(size 1.27 1.27)
					(thickness 0.15)
				)
				(justify left bottom)
				(hide yes)
			)
		)
		(property "Manufacturer" "Murata"
			(at 330.2 104.14 0)
			(effects
				(font
					(size 1.27 1.27)
					(thickness 0.15)
				)
				(justify left bottom)
				(hide yes)
			)
		)
		(property "License" "Apache-2.0"
			(at 332.74 104.14 0)
			(effects
				(font
					(size 1.27 1.27)
					(thickness 0.15)
				)
				(justify left bottom)
				(hide yes)
			)
		)
		(property "Author" "Antmicro"
			(at 335.28 104.14 0)
			(effects
				(font
					(size 1.27 1.27)
					(thickness 0.15)
				)
				(justify left bottom)
				(hide yes)
			)
		)
		(property "Val" "100n"
			(at 312.42 123.1836 90)
			(effects
				(font
					(size 1.27 1.27)
					(thickness 0.15)
				)
				(justify right)
			)
		)
		(property "Voltage" "50V"
			(at 337.82 104.14 0)
			(effects
				(font
					(size 1.27 1.27)
				)
				(justify left bottom)
				(hide yes)
			)
		)
		(property "Dielectric" "X5R"
			(at 340.36 104.14 0)
			(effects
				(font
					(size 1.27 1.27)
				)
				(justify left bottom)
				(hide yes)
			)
		)
		(property "Public" ""
			(at 342.9 104.14 0)
			(effects
				(font
					(size 1.27 1.27)
				)
				(justify left bottom)
				(hide yes)
			)
		)
		(pin "1"
		)
		(pin "2"
		)
		(instances
			(project "polarfire-som"
				(path ""
					(reference "C206")
					(unit 1)
				)
			)
		)
	)
	(symbol
		(lib_id "antmicroCapacitors0402:C_10u_10V_0402")
		(at 354.33 106.68 90)
		(unit 1)
		(exclude_from_sim no)
		(in_bom yes)
		(on_board yes)
		(dnp no)
		(property "Reference" "C208"
			(at 351.79 102.8636 90)
			(effects
				(font
					(size 1.27 1.27)
					(thickness 0.15)
				)
				(justify left)
			)
		)
		(property "Value" "C_10u_10V_0402"
			(at 364.49 86.36 0)
			(effects
				(font
					(size 1.27 1.27)
					(thickness 0.15)
				)
				(justify left bottom)
				(hide yes)
			)
		)
		(property "Footprint" "antmicro-footprints:C_0402_1005Metric"
			(at 367.03 86.36 0)
			(effects
				(font
					(size 1.27 1.27)
					(thickness 0.15)
				)
				(justify left bottom)
				(hide yes)
			)
		)
		(property "Datasheet" "https://www.murata.com/products/productdetail?partno=GRM155R61A106ME11%23"
			(at 369.57 86.36 0)
			(effects
				(font
					(size 1.27 1.27)
					(thickness 0.15)
				)
				(justify left bottom)
				(hide yes)
			)
		)
		(property "Description" "Multilayer Ceramic Capacitors MLCC - SMD/SMT 10 uF 10 VDC 20% 0402 X5R"
			(at 354.33 106.68 0)
			(effects
				(font
					(size 1.27 1.27)
				)
				(hide yes)
			)
		)
		(property "MPN" "GRM155R61A106ME11D"
			(at 372.11 86.36 0)
			(effects
				(font
					(size 1.27 1.27)
					(thickness 0.15)
				)
				(justify left bottom)
				(hide yes)
			)
		)
		(property "Manufacturer" "Murata"
			(at 374.65 86.36 0)
			(effects
				(font
					(size 1.27 1.27)
					(thickness 0.15)
				)
				(justify left bottom)
				(hide yes)
			)
		)
		(property "License" "Apache-2.0"
			(at 377.19 86.36 0)
			(effects
				(font
					(size 1.27 1.27)
					(thickness 0.15)
				)
				(justify left bottom)
				(hide yes)
			)
		)
		(property "Author" "Antmicro"
			(at 379.73 86.36 0)
			(effects
				(font
					(size 1.27 1.27)
					(thickness 0.15)
				)
				(justify left bottom)
				(hide yes)
			)
		)
		(property "Val" "10u"
			(at 351.79 105.4036 90)
			(effects
				(font
					(size 1.27 1.27)
					(thickness 0.15)
				)
				(justify left)
			)
		)
		(property "Voltage" "10V"
			(at 382.27 86.36 0)
			(effects
				(font
					(size 1.27 1.27)
				)
				(justify left bottom)
				(hide yes)
			)
		)
		(property "Dielectric" "X5R"
			(at 384.81 86.36 0)
			(effects
				(font
					(size 1.27 1.27)
				)
				(justify left bottom)
				(hide yes)
			)
		)
		(property "Public" ""
			(at 387.35 86.36 0)
			(effects
				(font
					(size 1.27 1.27)
				)
				(justify left bottom)
				(hide yes)
			)
		)
		(pin "1"
		)
		(pin "2"
		)
		(instances
			(project "polarfire-som"
				(path ""
					(reference "C208")
					(unit 1)
				)
			)
		)
	)
	(symbol
		(lib_id "antmicropower:GND")
		(at 303.53 144.78 0)
		(unit 1)
		(exclude_from_sim no)
		(in_bom yes)
		(on_board yes)
		(dnp no)
		(property "Reference" "#PWR0196"
			(at 312.42 147.32 0)
			(effects
				(font
					(size 1.27 1.27)
					(thickness 0.15)
				)
				(justify left bottom)
				(hide yes)
			)
		)
		(property "Value" "GND"
			(at 303.53 148.59 0)
			(effects
				(font
					(size 1.27 1.27)
					(thickness 0.15)
				)
			)
		)
		(property "Footprint" ""
			(at 312.42 152.4 0)
			(effects
				(font
					(size 1.27 1.27)
					(thickness 0.15)
				)
				(justify left bottom)
				(hide yes)
			)
		)
		(property "Datasheet" ""
			(at 312.42 157.48 0)
			(effects
				(font
					(size 1.27 1.27)
					(thickness 0.15)
				)
				(justify left bottom)
				(hide yes)
			)
		)
		(property "Description" ""
			(at 303.53 144.78 0)
			(effects
				(font
					(size 1.27 1.27)
				)
				(hide yes)
			)
		)
		(property "Author" "Antmicro"
			(at 312.42 152.4 0)
			(effects
				(font
					(size 1.27 1.27)
					(thickness 0.15)
				)
				(justify left bottom)
				(hide yes)
			)
		)
		(property "License" "Apache-2.0"
			(at 312.42 154.94 0)
			(effects
				(font
					(size 1.27 1.27)
					(thickness 0.15)
				)
				(justify left bottom)
				(hide yes)
			)
		)
		(pin "1"
		)
		(instances
			(project "polarfire-som"
				(path ""
					(reference "#PWR0196")
					(unit 1)
				)
			)
		)
	)
	(symbol
		(lib_id "antmicroCapacitors0402:C_1u_0402")
		(at 254 124.46 270)
		(mirror x)
		(unit 1)
		(exclude_from_sim no)
		(in_bom yes)
		(on_board yes)
		(dnp no)
		(property "Reference" "C197"
			(at 251.46 120.6435 90)
			(effects
				(font
					(size 1.27 1.27)
					(thickness 0.15)
				)
				(justify right)
			)
		)
		(property "Value" "C_1u_0402"
			(at 243.84 104.14 0)
			(effects
				(font
					(size 1.27 1.27)
					(thickness 0.15)
				)
				(justify left bottom)
				(hide yes)
			)
		)
		(property "Footprint" "antmicro-footprints:C_0402_1005Metric"
			(at 241.3 104.14 0)
			(effects
				(font
					(size 1.27 1.27)
					(thickness 0.15)
				)
				(justify left bottom)
				(hide yes)
			)
		)
		(property "Datasheet" "https://product.tdk.com/en/search/capacitor/ceramic/mlcc/info?part_no=C1005X6S1A105K050BC"
			(at 238.76 104.14 0)
			(effects
				(font
					(size 1.27 1.27)
					(thickness 0.15)
				)
				(justify left bottom)
				(hide yes)
			)
		)
		(property "Description" "SMD Multilayer Ceramic Capacitor, 1 µF, 10 V, 0402 [1005 Metric], ± 10%, X6S, C"
			(at 254 124.46 0)
			(effects
				(font
					(size 1.27 1.27)
				)
				(hide yes)
			)
		)
		(property "MPN" "C1005X6S1A105K050BC"
			(at 236.22 104.14 0)
			(effects
				(font
					(size 1.27 1.27)
					(thickness 0.15)
				)
				(justify left bottom)
				(hide yes)
			)
		)
		(property "Manufacturer" "TDK"
			(at 233.68 104.14 0)
			(effects
				(font
					(size 1.27 1.27)
					(thickness 0.15)
				)
				(justify left bottom)
				(hide yes)
			)
		)
		(property "License" "Apache-2.0"
			(at 231.14 104.14 0)
			(effects
				(font
					(size 1.27 1.27)
					(thickness 0.15)
				)
				(justify left bottom)
				(hide yes)
			)
		)
		(property "Author" "Antmicro"
			(at 228.6 104.14 0)
			(effects
				(font
					(size 1.27 1.27)
					(thickness 0.15)
				)
				(justify left bottom)
				(hide yes)
			)
		)
		(property "Val" "1u"
			(at 251.46 123.1835 90)
			(effects
				(font
					(size 1.27 1.27)
					(thickness 0.15)
				)
				(justify right)
			)
		)
		(property "Voltage" ""
			(at 226.06 104.14 0)
			(effects
				(font
					(size 1.27 1.27)
				)
				(justify left bottom)
				(hide yes)
			)
		)
		(property "Dielectric" ""
			(at 223.52 104.14 0)
			(effects
				(font
					(size 1.27 1.27)
				)
				(justify left bottom)
				(hide yes)
			)
		)
		(property "Public" ""
			(at 220.98 104.14 0)
			(effects
				(font
					(size 1.27 1.27)
				)
				(justify left bottom)
				(hide yes)
			)
		)
		(pin "1"
		)
		(pin "2"
		)
		(instances
			(project "polarfire-som"
				(path ""
					(reference "C197")
					(unit 1)
				)
			)
		)
	)
	(symbol
		(lib_id "antmicropower:GND")
		(at 360.68 109.22 0)
		(unit 1)
		(exclude_from_sim no)
		(in_bom yes)
		(on_board yes)
		(dnp no)
		(property "Reference" "#PWR0197"
			(at 369.57 111.76 0)
			(effects
				(font
					(size 1.27 1.27)
					(thickness 0.15)
				)
				(justify left bottom)
				(hide yes)
			)
		)
		(property "Value" "GND"
			(at 360.68 113.03 0)
			(effects
				(font
					(size 1.27 1.27)
					(thickness 0.15)
				)
			)
		)
		(property "Footprint" ""
			(at 369.57 116.84 0)
			(effects
				(font
					(size 1.27 1.27)
					(thickness 0.15)
				)
				(justify left bottom)
				(hide yes)
			)
		)
		(property "Datasheet" ""
			(at 369.57 121.92 0)
			(effects
				(font
					(size 1.27 1.27)
					(thickness 0.15)
				)
				(justify left bottom)
				(hide yes)
			)
		)
		(property "Description" ""
			(at 360.68 109.22 0)
			(effects
				(font
					(size 1.27 1.27)
				)
				(hide yes)
			)
		)
		(property "Author" "Antmicro"
			(at 369.57 116.84 0)
			(effects
				(font
					(size 1.27 1.27)
					(thickness 0.15)
				)
				(justify left bottom)
				(hide yes)
			)
		)
		(property "License" "Apache-2.0"
			(at 369.57 119.38 0)
			(effects
				(font
					(size 1.27 1.27)
					(thickness 0.15)
				)
				(justify left bottom)
				(hide yes)
			)
		)
		(pin "1"
		)
		(instances
			(project "polarfire-som"
				(path ""
					(reference "#PWR0197")
					(unit 1)
				)
			)
		)
	)
	(symbol
		(lib_id "antmicroFerriteBeadsandChips:FB_120Z_1.2A_TDK-MPZ_0402")
		(at 290.83 135.89 180)
		(unit 1)
		(exclude_from_sim no)
		(in_bom yes)
		(on_board yes)
		(dnp no)
		(fields_autoplaced yes)
		(property "Reference" "FB9"
			(at 288.3281 129.54 0)
			(effects
				(font
					(size 1.27 1.27)
					(thickness 0.15)
				)
			)
		)
		(property "Value" "FB_120Z_1.2A_TDK-MPZ_0402"
			(at 276.86 133.35 0)
			(effects
				(font
					(size 1.27 1.27)
					(thickness 0.15)
				)
				(justify left bottom)
				(hide yes)
			)
		)
		(property "Footprint" "antmicro-footprints:FB_0402_1005Metric"
			(at 276.86 128.27 0)
			(effects
				(font
					(size 1.27 1.27)
					(thickness 0.15)
				)
				(justify left bottom)
				(hide yes)
			)
		)
		(property "Datasheet" "https://product.tdk.com/en/search/emc/emc/beads/info?part_no=MPZ1005S121CT000"
			(at 276.86 125.73 0)
			(effects
				(font
					(size 1.27 1.27)
					(thickness 0.15)
				)
				(justify left bottom)
				(hide yes)
			)
		)
		(property "Description" "Ferrite Bead, 0402 [1005 Metric], 120 ohm, 1.2A, MPZ, 0.06 ohm, ± 25%, DC Power line"
			(at 290.83 135.89 0)
			(effects
				(font
					(size 1.27 1.27)
				)
				(hide yes)
			)
		)
		(property "Val" "120Z/1.2A"
			(at 288.3281 132.08 0)
			(effects
				(font
					(size 1.27 1.27)
				)
			)
		)
		(property "MPN" "MPZ1005S121CT000"
			(at 276.86 123.19 0)
			(effects
				(font
					(size 1.27 1.27)
					(thickness 0.15)
				)
				(justify left bottom)
				(hide yes)
			)
		)
		(property "Manufacturer" "TDK"
			(at 276.86 120.65 0)
			(effects
				(font
					(size 1.27 1.27)
					(thickness 0.15)
				)
				(justify left bottom)
				(hide yes)
			)
		)
		(property "Current" ""
			(at 270.51 113.03 0)
			(effects
				(font
					(size 1.27 1.27)
					(thickness 0.15)
				)
				(justify left bottom)
				(hide yes)
			)
		)
		(property "Author" "Antmicro"
			(at 276.86 118.11 0)
			(effects
				(font
					(size 1.27 1.27)
					(thickness 0.15)
				)
				(justify left bottom)
				(hide yes)
			)
		)
		(property "License" "Apache-2.0"
			(at 276.86 115.57 0)
			(effects
				(font
					(size 1.27 1.27)
					(thickness 0.15)
				)
				(justify left bottom)
				(hide yes)
			)
		)
		(property "Public" ""
			(at 270.51 120.65 0)
			(effects
				(font
					(size 1.27 1.27)
				)
				(justify left bottom)
				(hide yes)
			)
		)
		(pin "1"
		)
		(pin "2"
		)
		(instances
			(project "polarfire-som"
				(path ""
					(reference "FB9")
					(unit 1)
				)
			)
		)
	)
	(symbol
		(lib_id "antmicropower:GND")
		(at 360.68 144.78 0)
		(unit 1)
		(exclude_from_sim no)
		(in_bom yes)
		(on_board yes)
		(dnp no)
		(property "Reference" "#PWR0178"
			(at 369.57 147.32 0)
			(effects
				(font
					(size 1.27 1.27)
					(thickness 0.15)
				)
				(justify left bottom)
				(hide yes)
			)
		)
		(property "Value" "GND"
			(at 360.68 148.59 0)
			(effects
				(font
					(size 1.27 1.27)
					(thickness 0.15)
				)
			)
		)
		(property "Footprint" ""
			(at 369.57 152.4 0)
			(effects
				(font
					(size 1.27 1.27)
					(thickness 0.15)
				)
				(justify left bottom)
				(hide yes)
			)
		)
		(property "Datasheet" ""
			(at 369.57 157.48 0)
			(effects
				(font
					(size 1.27 1.27)
					(thickness 0.15)
				)
				(justify left bottom)
				(hide yes)
			)
		)
		(property "Description" ""
			(at 360.68 144.78 0)
			(effects
				(font
					(size 1.27 1.27)
				)
				(hide yes)
			)
		)
		(property "Author" "Antmicro"
			(at 369.57 152.4 0)
			(effects
				(font
					(size 1.27 1.27)
					(thickness 0.15)
				)
				(justify left bottom)
				(hide yes)
			)
		)
		(property "License" "Apache-2.0"
			(at 369.57 154.94 0)
			(effects
				(font
					(size 1.27 1.27)
					(thickness 0.15)
				)
				(justify left bottom)
				(hide yes)
			)
		)
		(pin "1"
		)
		(instances
			(project "polarfire-som"
				(path ""
					(reference "#PWR0178")
					(unit 1)
				)
			)
		)
	)
	(symbol
		(lib_id "antmicroCapacitors0402:C_1u_0402")
		(at 260.35 142.24 90)
		(unit 1)
		(exclude_from_sim no)
		(in_bom yes)
		(on_board yes)
		(dnp no)
		(fields_autoplaced yes)
		(property "Reference" "C200"
			(at 262.89 138.4235 90)
			(effects
				(font
					(size 1.27 1.27)
					(thickness 0.15)
				)
				(justify right)
			)
		)
		(property "Value" "C_1u_0402"
			(at 270.51 121.92 0)
			(effects
				(font
					(size 1.27 1.27)
					(thickness 0.15)
				)
				(justify left bottom)
				(hide yes)
			)
		)
		(property "Footprint" "antmicro-footprints:C_0402_1005Metric"
			(at 273.05 121.92 0)
			(effects
				(font
					(size 1.27 1.27)
					(thickness 0.15)
				)
				(justify left bottom)
				(hide yes)
			)
		)
		(property "Datasheet" "https://product.tdk.com/en/search/capacitor/ceramic/mlcc/info?part_no=C1005X6S1A105K050BC"
			(at 275.59 121.92 0)
			(effects
				(font
					(size 1.27 1.27)
					(thickness 0.15)
				)
				(justify left bottom)
				(hide yes)
			)
		)
		(property "Description" "SMD Multilayer Ceramic Capacitor, 1 µF, 10 V, 0402 [1005 Metric], ± 10%, X6S, C"
			(at 260.35 142.24 0)
			(effects
				(font
					(size 1.27 1.27)
				)
				(hide yes)
			)
		)
		(property "MPN" "C1005X6S1A105K050BC"
			(at 278.13 121.92 0)
			(effects
				(font
					(size 1.27 1.27)
					(thickness 0.15)
				)
				(justify left bottom)
				(hide yes)
			)
		)
		(property "Manufacturer" "TDK"
			(at 280.67 121.92 0)
			(effects
				(font
					(size 1.27 1.27)
					(thickness 0.15)
				)
				(justify left bottom)
				(hide yes)
			)
		)
		(property "License" "Apache-2.0"
			(at 283.21 121.92 0)
			(effects
				(font
					(size 1.27 1.27)
					(thickness 0.15)
				)
				(justify left bottom)
				(hide yes)
			)
		)
		(property "Author" "Antmicro"
			(at 285.75 121.92 0)
			(effects
				(font
					(size 1.27 1.27)
					(thickness 0.15)
				)
				(justify left bottom)
				(hide yes)
			)
		)
		(property "Val" "1u"
			(at 262.89 140.9635 90)
			(effects
				(font
					(size 1.27 1.27)
					(thickness 0.15)
				)
				(justify right)
			)
		)
		(property "Voltage" ""
			(at 288.29 121.92 0)
			(effects
				(font
					(size 1.27 1.27)
				)
				(justify left bottom)
				(hide yes)
			)
		)
		(property "Dielectric" ""
			(at 290.83 121.92 0)
			(effects
				(font
					(size 1.27 1.27)
				)
				(justify left bottom)
				(hide yes)
			)
		)
		(property "Public" ""
			(at 293.37 121.92 0)
			(effects
				(font
					(size 1.27 1.27)
				)
				(justify left bottom)
				(hide yes)
			)
		)
		(pin "1"
		)
		(pin "2"
		)
		(instances
			(project "polarfire-som"
				(path ""
					(reference "C200")
					(unit 1)
				)
			)
		)
	)
	(symbol
		(lib_id "antmicroCapacitors0402:C_10u_0402")
		(at 297.18 142.24 270)
		(mirror x)
		(unit 1)
		(exclude_from_sim no)
		(in_bom yes)
		(on_board yes)
		(dnp no)
		(fields_autoplaced yes)
		(property "Reference" "C207"
			(at 294.64 138.4235 90)
			(effects
				(font
					(size 1.27 1.27)
					(thickness 0.15)
				)
				(justify right)
			)
		)
		(property "Value" "C_10u_0402"
			(at 287.02 121.92 0)
			(effects
				(font
					(size 1.27 1.27)
					(thickness 0.15)
				)
				(justify left bottom)
				(hide yes)
			)
		)
		(property "Footprint" "antmicro-footprints:C_0402_1005Metric"
			(at 284.48 121.92 0)
			(effects
				(font
					(size 1.27 1.27)
					(thickness 0.15)
				)
				(justify left bottom)
				(hide yes)
			)
		)
		(property "Datasheet" "https://www.yageo.com/en/Chart/Download/pdf/CC0402MRX5R5BB106"
			(at 281.94 121.92 0)
			(effects
				(font
					(size 1.27 1.27)
					(thickness 0.15)
				)
				(justify left bottom)
				(hide yes)
			)
		)
		(property "Description" "SMD Multilayer Ceramic Capacitor, 10 µF, 6.3 V, 0402 [1005 Metric], ± 20%, X5R, CC Series"
			(at 297.18 142.24 0)
			(effects
				(font
					(size 1.27 1.27)
				)
				(hide yes)
			)
		)
		(property "MPN" "CC0402MRX5R5BB106"
			(at 279.4 121.92 0)
			(effects
				(font
					(size 1.27 1.27)
					(thickness 0.15)
				)
				(justify left bottom)
				(hide yes)
			)
		)
		(property "Manufacturer" "YAGEO"
			(at 276.86 121.92 0)
			(effects
				(font
					(size 1.27 1.27)
					(thickness 0.15)
				)
				(justify left bottom)
				(hide yes)
			)
		)
		(property "License" "Apache-2.0"
			(at 274.32 121.92 0)
			(effects
				(font
					(size 1.27 1.27)
					(thickness 0.15)
				)
				(justify left bottom)
				(hide yes)
			)
		)
		(property "Author" "Antmicro"
			(at 271.78 121.92 0)
			(effects
				(font
					(size 1.27 1.27)
					(thickness 0.15)
				)
				(justify left bottom)
				(hide yes)
			)
		)
		(property "Val" "10u"
			(at 294.64 140.9635 90)
			(effects
				(font
					(size 1.27 1.27)
					(thickness 0.15)
				)
				(justify right)
			)
		)
		(property "Voltage" ""
			(at 269.24 121.92 0)
			(effects
				(font
					(size 1.27 1.27)
				)
				(justify left bottom)
				(hide yes)
			)
		)
		(property "Dielectric" ""
			(at 266.7 121.92 0)
			(effects
				(font
					(size 1.27 1.27)
				)
				(justify left bottom)
				(hide yes)
			)
		)
		(property "Public" ""
			(at 264.16 121.92 0)
			(effects
				(font
					(size 1.27 1.27)
				)
				(justify left bottom)
				(hide yes)
			)
		)
		(pin "1"
		)
		(pin "2"
		)
		(instances
			(project "polarfire-som"
				(path ""
					(reference "C207")
					(unit 1)
				)
			)
		)
	)
	(symbol
		(lib_id "antmicroCapacitors0402:C_10u_10V_0402")
		(at 354.33 124.46 90)
		(unit 1)
		(exclude_from_sim no)
		(in_bom yes)
		(on_board yes)
		(dnp no)
		(property "Reference" "C209"
			(at 351.79 120.6436 90)
			(effects
				(font
					(size 1.27 1.27)
					(thickness 0.15)
				)
				(justify left)
			)
		)
		(property "Value" "C_10u_10V_0402"
			(at 364.49 104.14 0)
			(effects
				(font
					(size 1.27 1.27)
					(thickness 0.15)
				)
				(justify left bottom)
				(hide yes)
			)
		)
		(property "Footprint" "antmicro-footprints:C_0402_1005Metric"
			(at 367.03 104.14 0)
			(effects
				(font
					(size 1.27 1.27)
					(thickness 0.15)
				)
				(justify left bottom)
				(hide yes)
			)
		)
		(property "Datasheet" "https://www.murata.com/products/productdetail?partno=GRM155R61A106ME11%23"
			(at 369.57 104.14 0)
			(effects
				(font
					(size 1.27 1.27)
					(thickness 0.15)
				)
				(justify left bottom)
				(hide yes)
			)
		)
		(property "Description" "Multilayer Ceramic Capacitors MLCC - SMD/SMT 10 uF 10 VDC 20% 0402 X5R"
			(at 354.33 124.46 0)
			(effects
				(font
					(size 1.27 1.27)
				)
				(hide yes)
			)
		)
		(property "MPN" "GRM155R61A106ME11D"
			(at 372.11 104.14 0)
			(effects
				(font
					(size 1.27 1.27)
					(thickness 0.15)
				)
				(justify left bottom)
				(hide yes)
			)
		)
		(property "Manufacturer" "Murata"
			(at 374.65 104.14 0)
			(effects
				(font
					(size 1.27 1.27)
					(thickness 0.15)
				)
				(justify left bottom)
				(hide yes)
			)
		)
		(property "License" "Apache-2.0"
			(at 377.19 104.14 0)
			(effects
				(font
					(size 1.27 1.27)
					(thickness 0.15)
				)
				(justify left bottom)
				(hide yes)
			)
		)
		(property "Author" "Antmicro"
			(at 379.73 104.14 0)
			(effects
				(font
					(size 1.27 1.27)
					(thickness 0.15)
				)
				(justify left bottom)
				(hide yes)
			)
		)
		(property "Val" "10u"
			(at 351.79 123.1836 90)
			(effects
				(font
					(size 1.27 1.27)
					(thickness 0.15)
				)
				(justify left)
			)
		)
		(property "Voltage" "10V"
			(at 382.27 104.14 0)
			(effects
				(font
					(size 1.27 1.27)
				)
				(justify left bottom)
				(hide yes)
			)
		)
		(property "Dielectric" "X5R"
			(at 384.81 104.14 0)
			(effects
				(font
					(size 1.27 1.27)
				)
				(justify left bottom)
				(hide yes)
			)
		)
		(property "Public" ""
			(at 387.35 104.14 0)
			(effects
				(font
					(size 1.27 1.27)
				)
				(justify left bottom)
				(hide yes)
			)
		)
		(pin "1"
		)
		(pin "2"
		)
		(instances
			(project "polarfire-som"
				(path ""
					(reference "C209")
					(unit 1)
				)
			)
		)
	)
	(symbol
		(lib_id "antmicropower:+1V2")
		(at 238.76 118.11 90)
		(unit 1)
		(exclude_from_sim no)
		(in_bom yes)
		(on_board yes)
		(dnp no)
		(property "Reference" "#PWR076"
			(at 242.57 118.11 0)
			(effects
				(font
					(size 1.27 1.27)
				)
				(hide yes)
			)
		)
		(property "Value" "+1V2"
			(at 232.41 118.11 90)
			(effects
				(font
					(size 1.27 1.27)
				)
			)
		)
		(property "Footprint" ""
			(at 238.76 118.11 0)
			(effects
				(font
					(size 1.27 1.27)
				)
				(hide yes)
			)
		)
		(property "Datasheet" ""
			(at 238.76 118.11 0)
			(effects
				(font
					(size 1.27 1.27)
				)
				(hide yes)
			)
		)
		(property "Description" ""
			(at 238.76 118.11 0)
			(effects
				(font
					(size 1.27 1.27)
				)
				(hide yes)
			)
		)
		(pin "1"
		)
		(instances
			(project "polarfire-som"
				(path ""
					(reference "#PWR076")
					(unit 1)
				)
			)
		)
	)
	(symbol
		(lib_id "antmicroFerriteBeadsandChips:FB_120Z_1.2A_TDK-MPZ_0402")
		(at 344.17 118.11 180)
		(unit 1)
		(exclude_from_sim no)
		(in_bom yes)
		(on_board yes)
		(dnp no)
		(fields_autoplaced yes)
		(property "Reference" "FB8"
			(at 341.6681 111.76 0)
			(effects
				(font
					(size 1.27 1.27)
					(thickness 0.15)
				)
			)
		)
		(property "Value" "FB_120Z_1.2A_TDK-MPZ_0402"
			(at 330.2 115.57 0)
			(effects
				(font
					(size 1.27 1.27)
					(thickness 0.15)
				)
				(justify left bottom)
				(hide yes)
			)
		)
		(property "Footprint" "antmicro-footprints:FB_0402_1005Metric"
			(at 330.2 110.49 0)
			(effects
				(font
					(size 1.27 1.27)
					(thickness 0.15)
				)
				(justify left bottom)
				(hide yes)
			)
		)
		(property "Datasheet" "https://product.tdk.com/en/search/emc/emc/beads/info?part_no=MPZ1005S121CT000"
			(at 330.2 107.95 0)
			(effects
				(font
					(size 1.27 1.27)
					(thickness 0.15)
				)
				(justify left bottom)
				(hide yes)
			)
		)
		(property "Description" "Ferrite Bead, 0402 [1005 Metric], 120 ohm, 1.2A, MPZ, 0.06 ohm, ± 25%, DC Power line"
			(at 344.17 118.11 0)
			(effects
				(font
					(size 1.27 1.27)
				)
				(hide yes)
			)
		)
		(property "Val" "120Z/1.2A"
			(at 341.6681 114.3 0)
			(effects
				(font
					(size 1.27 1.27)
				)
			)
		)
		(property "MPN" "MPZ1005S121CT000"
			(at 330.2 105.41 0)
			(effects
				(font
					(size 1.27 1.27)
					(thickness 0.15)
				)
				(justify left bottom)
				(hide yes)
			)
		)
		(property "Manufacturer" "TDK"
			(at 330.2 102.87 0)
			(effects
				(font
					(size 1.27 1.27)
					(thickness 0.15)
				)
				(justify left bottom)
				(hide yes)
			)
		)
		(property "Current" ""
			(at 323.85 95.25 0)
			(effects
				(font
					(size 1.27 1.27)
					(thickness 0.15)
				)
				(justify left bottom)
				(hide yes)
			)
		)
		(property "Author" "Antmicro"
			(at 330.2 100.33 0)
			(effects
				(font
					(size 1.27 1.27)
					(thickness 0.15)
				)
				(justify left bottom)
				(hide yes)
			)
		)
		(property "License" "Apache-2.0"
			(at 330.2 97.79 0)
			(effects
				(font
					(size 1.27 1.27)
					(thickness 0.15)
				)
				(justify left bottom)
				(hide yes)
			)
		)
		(property "Public" ""
			(at 323.85 102.87 0)
			(effects
				(font
					(size 1.27 1.27)
				)
				(justify left bottom)
				(hide yes)
			)
		)
		(pin "1"
		)
		(pin "2"
		)
		(instances
			(project "polarfire-som"
				(path ""
					(reference "FB8")
					(unit 1)
				)
			)
		)
	)
	(symbol
		(lib_id "antmicropower:GND")
		(at 360.68 162.56 0)
		(unit 1)
		(exclude_from_sim no)
		(in_bom yes)
		(on_board yes)
		(dnp no)
		(property "Reference" "#PWR0179"
			(at 369.57 165.1 0)
			(effects
				(font
					(size 1.27 1.27)
					(thickness 0.15)
				)
				(justify left bottom)
				(hide yes)
			)
		)
		(property "Value" "GND"
			(at 360.68 166.37 0)
			(effects
				(font
					(size 1.27 1.27)
					(thickness 0.15)
				)
			)
		)
		(property "Footprint" ""
			(at 369.57 170.18 0)
			(effects
				(font
					(size 1.27 1.27)
					(thickness 0.15)
				)
				(justify left bottom)
				(hide yes)
			)
		)
		(property "Datasheet" ""
			(at 369.57 175.26 0)
			(effects
				(font
					(size 1.27 1.27)
					(thickness 0.15)
				)
				(justify left bottom)
				(hide yes)
			)
		)
		(property "Description" ""
			(at 360.68 162.56 0)
			(effects
				(font
					(size 1.27 1.27)
				)
				(hide yes)
			)
		)
		(property "Author" "Antmicro"
			(at 369.57 170.18 0)
			(effects
				(font
					(size 1.27 1.27)
					(thickness 0.15)
				)
				(justify left bottom)
				(hide yes)
			)
		)
		(property "License" "Apache-2.0"
			(at 369.57 172.72 0)
			(effects
				(font
					(size 1.27 1.27)
					(thickness 0.15)
				)
				(justify left bottom)
				(hide yes)
			)
		)
		(pin "1"
		)
		(instances
			(project "polarfire-som"
				(path ""
					(reference "#PWR0179")
					(unit 1)
				)
			)
		)
	)
	(symbol
		(lib_id "antmicroResistors0402:R_10k_0402")
		(at 72.39 83.82 0)
		(unit 1)
		(exclude_from_sim no)
		(in_bom yes)
		(on_board yes)
		(dnp no)
		(fields_autoplaced yes)
		(property "Reference" "R117"
			(at 74.93 77.47 0)
			(effects
				(font
					(size 1.27 1.27)
					(thickness 0.15)
				)
			)
		)
		(property "Value" "R_10k_0402"
			(at 92.71 96.52 0)
			(effects
				(font
					(size 1.27 1.27)
					(thickness 0.15)
				)
				(justify left bottom)
				(hide yes)
			)
		)
		(property "Footprint" "antmicro-footprints:R_0402_1005Metric"
			(at 92.71 99.06 0)
			(effects
				(font
					(size 1.27 1.27)
					(thickness 0.15)
				)
				(justify left bottom)
				(hide yes)
			)
		)
		(property "Datasheet" "https://www.bourns.com/docs/product-datasheets/cr.pdf"
			(at 92.71 101.6 0)
			(effects
				(font
					(size 1.27 1.27)
					(thickness 0.15)
				)
				(justify left bottom)
				(hide yes)
			)
		)
		(property "Description" "SMD Chip Resistor, 10 kohm, ± 1%, 62.5 mW, 0402 [1005 Metric], Thick Film, General Purpose"
			(at 72.39 83.82 0)
			(effects
				(font
					(size 1.27 1.27)
				)
				(hide yes)
			)
		)
		(property "MPN" "CR0402-FX-1002GLF"
			(at 92.71 104.14 0)
			(effects
				(font
					(size 1.27 1.27)
					(thickness 0.15)
				)
				(justify left bottom)
				(hide yes)
			)
		)
		(property "Manufacturer" "Bourns"
			(at 92.71 106.68 0)
			(effects
				(font
					(size 1.27 1.27)
					(thickness 0.15)
				)
				(justify left bottom)
				(hide yes)
			)
		)
		(property "License" "Apache-2.0"
			(at 92.71 109.22 0)
			(effects
				(font
					(size 1.27 1.27)
					(thickness 0.15)
				)
				(justify left bottom)
				(hide yes)
			)
		)
		(property "Author" "Antmicro"
			(at 92.71 111.76 0)
			(effects
				(font
					(size 1.27 1.27)
					(thickness 0.15)
				)
				(justify left bottom)
				(hide yes)
			)
		)
		(property "Val" "10k"
			(at 74.93 80.01 0)
			(effects
				(font
					(size 1.27 1.27)
					(thickness 0.15)
				)
			)
		)
		(property "Tolerance" "1%"
			(at 92.71 93.98 0)
			(effects
				(font
					(size 1.27 1.27)
				)
				(justify left bottom)
				(hide yes)
			)
		)
		(property "Public" ""
			(at 92.71 114.3 0)
			(effects
				(font
					(size 1.27 1.27)
				)
				(justify left bottom)
				(hide yes)
			)
		)
		(pin "1"
		)
		(pin "2"
		)
		(instances
			(project "polarfire-som"
				(path ""
					(reference "R117")
					(unit 1)
				)
			)
		)
	)
	(symbol
		(lib_id "antmicropower:PWR_FLAG")
		(at 361.95 153.67 270)
		(unit 1)
		(exclude_from_sim no)
		(in_bom yes)
		(on_board yes)
		(dnp no)
		(property "Reference" "#FLG013"
			(at 363.855 153.67 0)
			(effects
				(font
					(size 1.27 1.27)
				)
				(hide yes)
			)
		)
		(property "Value" "PWR_FLAG"
			(at 369.57 153.67 90)
			(effects
				(font
					(size 1.27 1.27)
				)
			)
		)
		(property "Footprint" ""
			(at 361.95 153.67 0)
			(effects
				(font
					(size 1.27 1.27)
				)
				(hide yes)
			)
		)
		(property "Datasheet" ""
			(at 361.95 153.67 0)
			(effects
				(font
					(size 1.27 1.27)
				)
				(hide yes)
			)
		)
		(property "Description" ""
			(at 361.95 153.67 0)
			(effects
				(font
					(size 1.27 1.27)
				)
				(hide yes)
			)
		)
		(pin "1"
		)
		(instances
			(project "polarfire-som"
				(path ""
					(reference "#FLG013")
					(unit 1)
				)
			)
		)
	)
	(symbol
		(lib_id "antmicroCapacitors0402:C_10u_10V_0402")
		(at 303.53 124.46 90)
		(unit 1)
		(exclude_from_sim no)
		(in_bom yes)
		(on_board yes)
		(dnp no)
		(property "Reference" "C202"
			(at 300.99 120.6436 90)
			(effects
				(font
					(size 1.27 1.27)
					(thickness 0.15)
				)
				(justify left)
			)
		)
		(property "Value" "C_10u_10V_0402"
			(at 313.69 104.14 0)
			(effects
				(font
					(size 1.27 1.27)
					(thickness 0.15)
				)
				(justify left bottom)
				(hide yes)
			)
		)
		(property "Footprint" "antmicro-footprints:C_0402_1005Metric"
			(at 316.23 104.14 0)
			(effects
				(font
					(size 1.27 1.27)
					(thickness 0.15)
				)
				(justify left bottom)
				(hide yes)
			)
		)
		(property "Datasheet" "https://www.murata.com/products/productdetail?partno=GRM155R61A106ME11%23"
			(at 318.77 104.14 0)
			(effects
				(font
					(size 1.27 1.27)
					(thickness 0.15)
				)
				(justify left bottom)
				(hide yes)
			)
		)
		(property "Description" "Multilayer Ceramic Capacitors MLCC - SMD/SMT 10 uF 10 VDC 20% 0402 X5R"
			(at 303.53 124.46 0)
			(effects
				(font
					(size 1.27 1.27)
				)
				(hide yes)
			)
		)
		(property "MPN" "GRM155R61A106ME11D"
			(at 321.31 104.14 0)
			(effects
				(font
					(size 1.27 1.27)
					(thickness 0.15)
				)
				(justify left bottom)
				(hide yes)
			)
		)
		(property "Manufacturer" "Murata"
			(at 323.85 104.14 0)
			(effects
				(font
					(size 1.27 1.27)
					(thickness 0.15)
				)
				(justify left bottom)
				(hide yes)
			)
		)
		(property "License" "Apache-2.0"
			(at 326.39 104.14 0)
			(effects
				(font
					(size 1.27 1.27)
					(thickness 0.15)
				)
				(justify left bottom)
				(hide yes)
			)
		)
		(property "Author" "Antmicro"
			(at 328.93 104.14 0)
			(effects
				(font
					(size 1.27 1.27)
					(thickness 0.15)
				)
				(justify left bottom)
				(hide yes)
			)
		)
		(property "Val" "10u"
			(at 300.99 123.1836 90)
			(effects
				(font
					(size 1.27 1.27)
					(thickness 0.15)
				)
				(justify left)
			)
		)
		(property "Voltage" "10V"
			(at 331.47 104.14 0)
			(effects
				(font
					(size 1.27 1.27)
				)
				(justify left bottom)
				(hide yes)
			)
		)
		(property "Dielectric" "X5R"
			(at 334.01 104.14 0)
			(effects
				(font
					(size 1.27 1.27)
				)
				(justify left bottom)
				(hide yes)
			)
		)
		(property "Public" ""
			(at 336.55 104.14 0)
			(effects
				(font
					(size 1.27 1.27)
				)
				(justify left bottom)
				(hide yes)
			)
		)
		(pin "1"
		)
		(pin "2"
		)
		(instances
			(project "polarfire-som"
				(path ""
					(reference "C202")
					(unit 1)
				)
			)
		)
	)
	(symbol
		(lib_id "antmicropower:VDDI")
		(at 234.95 99.06 0)
		(unit 1)
		(exclude_from_sim no)
		(in_bom yes)
		(on_board yes)
		(dnp no)
		(fields_autoplaced yes)
		(property "Reference" "#PWR0337"
			(at 234.95 102.87 0)
			(effects
				(font
					(size 1.27 1.27)
				)
				(hide yes)
			)
		)
		(property "Value" "VDD"
			(at 234.95 93.98 0)
			(effects
				(font
					(size 1.27 1.27)
				)
			)
		)
		(property "Footprint" ""
			(at 234.95 99.06 0)
			(effects
				(font
					(size 1.27 1.27)
				)
				(hide yes)
			)
		)
		(property "Datasheet" ""
			(at 234.95 99.06 0)
			(effects
				(font
					(size 1.27 1.27)
				)
				(hide yes)
			)
		)
		(property "Description" ""
			(at 234.95 99.06 0)
			(effects
				(font
					(size 1.27 1.27)
				)
				(hide yes)
			)
		)
		(pin "1"
		)
		(instances
			(project "polarfire-som"
				(path ""
					(reference "#PWR0337")
					(unit 1)
				)
			)
		)
	)
	(symbol
		(lib_id "antmicropower:+1V2")
		(at 335.28 118.11 90)
		(unit 1)
		(exclude_from_sim no)
		(in_bom yes)
		(on_board yes)
		(dnp no)
		(property "Reference" "#PWR081"
			(at 339.09 118.11 0)
			(effects
				(font
					(size 1.27 1.27)
				)
				(hide yes)
			)
		)
		(property "Value" "+1V2"
			(at 328.93 118.11 90)
			(effects
				(font
					(size 1.27 1.27)
				)
			)
		)
		(property "Footprint" ""
			(at 335.28 118.11 0)
			(effects
				(font
					(size 1.27 1.27)
				)
				(hide yes)
			)
		)
		(property "Datasheet" ""
			(at 335.28 118.11 0)
			(effects
				(font
					(size 1.27 1.27)
				)
				(hide yes)
			)
		)
		(property "Description" ""
			(at 335.28 118.11 0)
			(effects
				(font
					(size 1.27 1.27)
				)
				(hide yes)
			)
		)
		(pin "1"
		)
		(instances
			(project "polarfire-som"
				(path ""
					(reference "#PWR081")
					(unit 1)
				)
			)
		)
	)
	(symbol
		(lib_id "antmicroCapacitors0402:C_10u_10V_0402")
		(at 254 106.68 90)
		(unit 1)
		(exclude_from_sim no)
		(in_bom yes)
		(on_board yes)
		(dnp no)
		(property "Reference" "C196"
			(at 251.46 102.8636 90)
			(effects
				(font
					(size 1.27 1.27)
					(thickness 0.15)
				)
				(justify left)
			)
		)
		(property "Value" "C_10u_10V_0402"
			(at 264.16 86.36 0)
			(effects
				(font
					(size 1.27 1.27)
					(thickness 0.15)
				)
				(justify left bottom)
				(hide yes)
			)
		)
		(property "Footprint" "antmicro-footprints:C_0402_1005Metric"
			(at 266.7 86.36 0)
			(effects
				(font
					(size 1.27 1.27)
					(thickness 0.15)
				)
				(justify left bottom)
				(hide yes)
			)
		)
		(property "Datasheet" "https://www.murata.com/products/productdetail?partno=GRM155R61A106ME11%23"
			(at 269.24 86.36 0)
			(effects
				(font
					(size 1.27 1.27)
					(thickness 0.15)
				)
				(justify left bottom)
				(hide yes)
			)
		)
		(property "Description" "Multilayer Ceramic Capacitors MLCC - SMD/SMT 10 uF 10 VDC 20% 0402 X5R"
			(at 254 106.68 0)
			(effects
				(font
					(size 1.27 1.27)
				)
				(hide yes)
			)
		)
		(property "MPN" "GRM155R61A106ME11D"
			(at 271.78 86.36 0)
			(effects
				(font
					(size 1.27 1.27)
					(thickness 0.15)
				)
				(justify left bottom)
				(hide yes)
			)
		)
		(property "Manufacturer" "Murata"
			(at 274.32 86.36 0)
			(effects
				(font
					(size 1.27 1.27)
					(thickness 0.15)
				)
				(justify left bottom)
				(hide yes)
			)
		)
		(property "License" "Apache-2.0"
			(at 276.86 86.36 0)
			(effects
				(font
					(size 1.27 1.27)
					(thickness 0.15)
				)
				(justify left bottom)
				(hide yes)
			)
		)
		(property "Author" "Antmicro"
			(at 279.4 86.36 0)
			(effects
				(font
					(size 1.27 1.27)
					(thickness 0.15)
				)
				(justify left bottom)
				(hide yes)
			)
		)
		(property "Val" "10u"
			(at 251.46 105.4036 90)
			(effects
				(font
					(size 1.27 1.27)
					(thickness 0.15)
				)
				(justify left)
			)
		)
		(property "Voltage" "10V"
			(at 281.94 86.36 0)
			(effects
				(font
					(size 1.27 1.27)
				)
				(justify left bottom)
				(hide yes)
			)
		)
		(property "Dielectric" "X5R"
			(at 284.48 86.36 0)
			(effects
				(font
					(size 1.27 1.27)
				)
				(justify left bottom)
				(hide yes)
			)
		)
		(property "Public" ""
			(at 287.02 86.36 0)
			(effects
				(font
					(size 1.27 1.27)
				)
				(justify left bottom)
				(hide yes)
			)
		)
		(pin "1"
		)
		(pin "2"
		)
		(instances
			(project "polarfire-som"
				(path ""
					(reference "C196")
					(unit 1)
				)
			)
		)
	)
	(symbol
		(lib_id "antmicropower:GND")
		(at 309.88 127 0)
		(unit 1)
		(exclude_from_sim no)
		(in_bom yes)
		(on_board yes)
		(dnp no)
		(property "Reference" "#PWR0191"
			(at 318.77 129.54 0)
			(effects
				(font
					(size 1.27 1.27)
					(thickness 0.15)
				)
				(justify left bottom)
				(hide yes)
			)
		)
		(property "Value" "GND"
			(at 309.88 130.81 0)
			(effects
				(font
					(size 1.27 1.27)
					(thickness 0.15)
				)
			)
		)
		(property "Footprint" ""
			(at 318.77 134.62 0)
			(effects
				(font
					(size 1.27 1.27)
					(thickness 0.15)
				)
				(justify left bottom)
				(hide yes)
			)
		)
		(property "Datasheet" ""
			(at 318.77 139.7 0)
			(effects
				(font
					(size 1.27 1.27)
					(thickness 0.15)
				)
				(justify left bottom)
				(hide yes)
			)
		)
		(property "Description" ""
			(at 309.88 127 0)
			(effects
				(font
					(size 1.27 1.27)
				)
				(hide yes)
			)
		)
		(property "Author" "Antmicro"
			(at 318.77 134.62 0)
			(effects
				(font
					(size 1.27 1.27)
					(thickness 0.15)
				)
				(justify left bottom)
				(hide yes)
			)
		)
		(property "License" "Apache-2.0"
			(at 318.77 137.16 0)
			(effects
				(font
					(size 1.27 1.27)
					(thickness 0.15)
				)
				(justify left bottom)
				(hide yes)
			)
		)
		(pin "1"
		)
		(instances
			(project "polarfire-som"
				(path ""
					(reference "#PWR0191")
					(unit 1)
				)
			)
		)
	)
	(symbol
		(lib_id "antmicropower:GND")
		(at 172.72 163.83 0)
		(unit 1)
		(exclude_from_sim no)
		(in_bom yes)
		(on_board yes)
		(dnp no)
		(property "Reference" "#PWR0177"
			(at 181.61 166.37 0)
			(effects
				(font
					(size 1.27 1.27)
					(thickness 0.15)
				)
				(justify left bottom)
				(hide yes)
			)
		)
		(property "Value" "GND"
			(at 172.72 167.64 0)
			(effects
				(font
					(size 1.27 1.27)
					(thickness 0.15)
				)
			)
		)
		(property "Footprint" ""
			(at 181.61 171.45 0)
			(effects
				(font
					(size 1.27 1.27)
					(thickness 0.15)
				)
				(justify left bottom)
				(hide yes)
			)
		)
		(property "Datasheet" ""
			(at 181.61 176.53 0)
			(effects
				(font
					(size 1.27 1.27)
					(thickness 0.15)
				)
				(justify left bottom)
				(hide yes)
			)
		)
		(property "Description" ""
			(at 172.72 163.83 0)
			(effects
				(font
					(size 1.27 1.27)
				)
				(hide yes)
			)
		)
		(property "Author" "Antmicro"
			(at 181.61 171.45 0)
			(effects
				(font
					(size 1.27 1.27)
					(thickness 0.15)
				)
				(justify left bottom)
				(hide yes)
			)
		)
		(property "License" "Apache-2.0"
			(at 181.61 173.99 0)
			(effects
				(font
					(size 1.27 1.27)
					(thickness 0.15)
				)
				(justify left bottom)
				(hide yes)
			)
		)
		(pin "1"
		)
		(instances
			(project "polarfire-som"
				(path ""
					(reference "#PWR0177")
					(unit 1)
				)
			)
		)
	)
	(symbol
		(lib_id "antmicroCapacitors0402:C_10u_10V_0402")
		(at 354.33 142.24 90)
		(unit 1)
		(exclude_from_sim no)
		(in_bom yes)
		(on_board yes)
		(dnp no)
		(property "Reference" "C248"
			(at 351.79 138.4236 90)
			(effects
				(font
					(size 1.27 1.27)
					(thickness 0.15)
				)
				(justify left)
			)
		)
		(property "Value" "C_10u_10V_0402"
			(at 364.49 121.92 0)
			(effects
				(font
					(size 1.27 1.27)
					(thickness 0.15)
				)
				(justify left bottom)
				(hide yes)
			)
		)
		(property "Footprint" "antmicro-footprints:C_0402_1005Metric"
			(at 367.03 121.92 0)
			(effects
				(font
					(size 1.27 1.27)
					(thickness 0.15)
				)
				(justify left bottom)
				(hide yes)
			)
		)
		(property "Datasheet" "https://www.murata.com/products/productdetail?partno=GRM155R61A106ME11%23"
			(at 369.57 121.92 0)
			(effects
				(font
					(size 1.27 1.27)
					(thickness 0.15)
				)
				(justify left bottom)
				(hide yes)
			)
		)
		(property "Description" "Multilayer Ceramic Capacitors MLCC - SMD/SMT 10 uF 10 VDC 20% 0402 X5R"
			(at 354.33 142.24 0)
			(effects
				(font
					(size 1.27 1.27)
				)
				(hide yes)
			)
		)
		(property "MPN" "GRM155R61A106ME11D"
			(at 372.11 121.92 0)
			(effects
				(font
					(size 1.27 1.27)
					(thickness 0.15)
				)
				(justify left bottom)
				(hide yes)
			)
		)
		(property "Manufacturer" "Murata"
			(at 374.65 121.92 0)
			(effects
				(font
					(size 1.27 1.27)
					(thickness 0.15)
				)
				(justify left bottom)
				(hide yes)
			)
		)
		(property "License" "Apache-2.0"
			(at 377.19 121.92 0)
			(effects
				(font
					(size 1.27 1.27)
					(thickness 0.15)
				)
				(justify left bottom)
				(hide yes)
			)
		)
		(property "Author" "Antmicro"
			(at 379.73 121.92 0)
			(effects
				(font
					(size 1.27 1.27)
					(thickness 0.15)
				)
				(justify left bottom)
				(hide yes)
			)
		)
		(property "Val" "10u"
			(at 351.79 140.9636 90)
			(effects
				(font
					(size 1.27 1.27)
					(thickness 0.15)
				)
				(justify left)
			)
		)
		(property "Voltage" "10V"
			(at 382.27 121.92 0)
			(effects
				(font
					(size 1.27 1.27)
				)
				(justify left bottom)
				(hide yes)
			)
		)
		(property "Dielectric" "X5R"
			(at 384.81 121.92 0)
			(effects
				(font
					(size 1.27 1.27)
				)
				(justify left bottom)
				(hide yes)
			)
		)
		(property "Public" ""
			(at 387.35 121.92 0)
			(effects
				(font
					(size 1.27 1.27)
				)
				(justify left bottom)
				(hide yes)
			)
		)
		(pin "1"
		)
		(pin "2"
		)
		(instances
			(project "polarfire-som"
				(path ""
					(reference "C248")
					(unit 1)
				)
			)
		)
	)
	(symbol
		(lib_id "antmicropower:PWR_FLAG")
		(at 314.96 135.89 270)
		(unit 1)
		(exclude_from_sim no)
		(in_bom yes)
		(on_board yes)
		(dnp no)
		(property "Reference" "#FLG020"
			(at 316.865 135.89 0)
			(effects
				(font
					(size 1.27 1.27)
				)
				(hide yes)
			)
		)
		(property "Value" "PWR_FLAG"
			(at 318.77 133.35 90)
			(effects
				(font
					(size 1.27 1.27)
				)
			)
		)
		(property "Footprint" ""
			(at 314.96 135.89 0)
			(effects
				(font
					(size 1.27 1.27)
				)
				(hide yes)
			)
		)
		(property "Datasheet" ""
			(at 314.96 135.89 0)
			(effects
				(font
					(size 1.27 1.27)
				)
				(hide yes)
			)
		)
		(property "Description" ""
			(at 314.96 135.89 0)
			(effects
				(font
					(size 1.27 1.27)
				)
				(hide yes)
			)
		)
		(pin "1"
		)
		(instances
			(project "polarfire-som"
				(path ""
					(reference "#FLG020")
					(unit 1)
				)
			)
		)
	)
	(symbol
		(lib_id "antmicroCapacitors0402:C_100n_0402")
		(at 313.69 142.24 90)
		(unit 1)
		(exclude_from_sim no)
		(in_bom yes)
		(on_board yes)
		(dnp no)
		(fields_autoplaced yes)
		(property "Reference" "C215"
			(at 316.23 138.4236 90)
			(effects
				(font
					(size 1.27 1.27)
					(thickness 0.15)
				)
				(justify right)
			)
		)
		(property "Value" "C_100n_0402"
			(at 323.85 121.92 0)
			(effects
				(font
					(size 1.27 1.27)
					(thickness 0.15)
				)
				(justify left bottom)
				(hide yes)
			)
		)
		(property "Footprint" "antmicro-footprints:C_0402_1005Metric"
			(at 326.39 121.92 0)
			(effects
				(font
					(size 1.27 1.27)
					(thickness 0.15)
				)
				(justify left bottom)
				(hide yes)
			)
		)
		(property "Datasheet" "https://www.murata.com/products/productdetail?partno=GRM155R61H104KE14%23"
			(at 328.93 121.92 0)
			(effects
				(font
					(size 1.27 1.27)
					(thickness 0.15)
				)
				(justify left bottom)
				(hide yes)
			)
		)
		(property "Description" "SMD Multilayer Ceramic Capacitor, 0.1 µF, 50 V, 0402 [1005 Metric], ± 10%, X5R, GRM Series"
			(at 313.69 142.24 0)
			(effects
				(font
					(size 1.27 1.27)
				)
				(hide yes)
			)
		)
		(property "MPN" "GRM155R61H104KE14D"
			(at 331.47 121.92 0)
			(effects
				(font
					(size 1.27 1.27)
					(thickness 0.15)
				)
				(justify left bottom)
				(hide yes)
			)
		)
		(property "Manufacturer" "Murata"
			(at 334.01 121.92 0)
			(effects
				(font
					(size 1.27 1.27)
					(thickness 0.15)
				)
				(justify left bottom)
				(hide yes)
			)
		)
		(property "License" "Apache-2.0"
			(at 336.55 121.92 0)
			(effects
				(font
					(size 1.27 1.27)
					(thickness 0.15)
				)
				(justify left bottom)
				(hide yes)
			)
		)
		(property "Author" "Antmicro"
			(at 339.09 121.92 0)
			(effects
				(font
					(size 1.27 1.27)
					(thickness 0.15)
				)
				(justify left bottom)
				(hide yes)
			)
		)
		(property "Val" "100n"
			(at 316.23 140.9636 90)
			(effects
				(font
					(size 1.27 1.27)
					(thickness 0.15)
				)
				(justify right)
			)
		)
		(property "Voltage" "50V"
			(at 341.63 121.92 0)
			(effects
				(font
					(size 1.27 1.27)
				)
				(justify left bottom)
				(hide yes)
			)
		)
		(property "Dielectric" "X5R"
			(at 344.17 121.92 0)
			(effects
				(font
					(size 1.27 1.27)
				)
				(justify left bottom)
				(hide yes)
			)
		)
		(property "Public" ""
			(at 346.71 121.92 0)
			(effects
				(font
					(size 1.27 1.27)
				)
				(justify left bottom)
				(hide yes)
			)
		)
		(pin "1"
		)
		(pin "2"
		)
		(instances
			(project "polarfire-som"
				(path ""
					(reference "C215")
					(unit 1)
				)
			)
		)
	)
	(symbol
		(lib_id "antmicropower:+1V2")
		(at 281.94 135.89 90)
		(unit 1)
		(exclude_from_sim no)
		(in_bom yes)
		(on_board yes)
		(dnp no)
		(property "Reference" "#PWR077"
			(at 285.75 135.89 0)
			(effects
				(font
					(size 1.27 1.27)
				)
				(hide yes)
			)
		)
		(property "Value" "+1V2"
			(at 275.59 135.89 90)
			(effects
				(font
					(size 1.27 1.27)
				)
			)
		)
		(property "Footprint" ""
			(at 281.94 135.89 0)
			(effects
				(font
					(size 1.27 1.27)
				)
				(hide yes)
			)
		)
		(property "Datasheet" ""
			(at 281.94 135.89 0)
			(effects
				(font
					(size 1.27 1.27)
				)
				(hide yes)
			)
		)
		(property "Description" ""
			(at 281.94 135.89 0)
			(effects
				(font
					(size 1.27 1.27)
				)
				(hide yes)
			)
		)
		(pin "1"
		)
		(instances
			(project "polarfire-som"
				(path ""
					(reference "#PWR077")
					(unit 1)
				)
			)
		)
	)
	(symbol
		(lib_id "antmicroCapacitors0402:C_100n_0402")
		(at 260.35 106.68 90)
		(unit 1)
		(exclude_from_sim no)
		(in_bom yes)
		(on_board yes)
		(dnp no)
		(property "Reference" "C198"
			(at 262.89 102.8635 90)
			(effects
				(font
					(size 1.27 1.27)
					(thickness 0.15)
				)
				(justify right)
			)
		)
		(property "Value" "C_100n_0402"
			(at 270.51 86.36 0)
			(effects
				(font
					(size 1.27 1.27)
					(thickness 0.15)
				)
				(justify left bottom)
				(hide yes)
			)
		)
		(property "Footprint" "antmicro-footprints:C_0402_1005Metric"
			(at 273.05 86.36 0)
			(effects
				(font
					(size 1.27 1.27)
					(thickness 0.15)
				)
				(justify left bottom)
				(hide yes)
			)
		)
		(property "Datasheet" "https://www.murata.com/products/productdetail?partno=GRM155R61H104KE14%23"
			(at 275.59 86.36 0)
			(effects
				(font
					(size 1.27 1.27)
					(thickness 0.15)
				)
				(justify left bottom)
				(hide yes)
			)
		)
		(property "Description" "SMD Multilayer Ceramic Capacitor, 0.1 µF, 50 V, 0402 [1005 Metric], ± 10%, X5R, GRM Series"
			(at 260.35 106.68 0)
			(effects
				(font
					(size 1.27 1.27)
				)
				(hide yes)
			)
		)
		(property "MPN" "GRM155R61H104KE14D"
			(at 278.13 86.36 0)
			(effects
				(font
					(size 1.27 1.27)
					(thickness 0.15)
				)
				(justify left bottom)
				(hide yes)
			)
		)
		(property "Manufacturer" "Murata"
			(at 280.67 86.36 0)
			(effects
				(font
					(size 1.27 1.27)
					(thickness 0.15)
				)
				(justify left bottom)
				(hide yes)
			)
		)
		(property "License" "Apache-2.0"
			(at 283.21 86.36 0)
			(effects
				(font
					(size 1.27 1.27)
					(thickness 0.15)
				)
				(justify left bottom)
				(hide yes)
			)
		)
		(property "Author" "Antmicro"
			(at 285.75 86.36 0)
			(effects
				(font
					(size 1.27 1.27)
					(thickness 0.15)
				)
				(justify left bottom)
				(hide yes)
			)
		)
		(property "Val" "100n"
			(at 267.97 105.41 90)
			(effects
				(font
					(size 1.27 1.27)
					(thickness 0.15)
				)
				(justify left bottom)
			)
		)
		(property "Voltage" "50V"
			(at 288.29 86.36 0)
			(effects
				(font
					(size 1.27 1.27)
				)
				(justify left bottom)
				(hide yes)
			)
		)
		(property "Dielectric" "X5R"
			(at 290.83 86.36 0)
			(effects
				(font
					(size 1.27 1.27)
				)
				(justify left bottom)
				(hide yes)
			)
		)
		(property "Public" ""
			(at 293.37 86.36 0)
			(effects
				(font
					(size 1.27 1.27)
				)
				(justify left bottom)
				(hide yes)
			)
		)
		(pin "1"
		)
		(pin "2"
		)
		(instances
			(project "polarfire-som"
				(path ""
					(reference "C198")
					(unit 1)
				)
			)
		)
	)
	(symbol
		(lib_id "antmicroFerriteBeadsandChips:FB_120Z_1.2A_TDK-MPZ_0402")
		(at 290.83 118.11 180)
		(unit 1)
		(exclude_from_sim no)
		(in_bom yes)
		(on_board yes)
		(dnp no)
		(fields_autoplaced yes)
		(property "Reference" "FB6"
			(at 288.3281 111.76 0)
			(effects
				(font
					(size 1.27 1.27)
					(thickness 0.15)
				)
			)
		)
		(property "Value" "FB_120Z_1.2A_TDK-MPZ_0402"
			(at 276.86 115.57 0)
			(effects
				(font
					(size 1.27 1.27)
					(thickness 0.15)
				)
				(justify left bottom)
				(hide yes)
			)
		)
		(property "Footprint" "antmicro-footprints:FB_0402_1005Metric"
			(at 276.86 110.49 0)
			(effects
				(font
					(size 1.27 1.27)
					(thickness 0.15)
				)
				(justify left bottom)
				(hide yes)
			)
		)
		(property "Datasheet" "https://product.tdk.com/en/search/emc/emc/beads/info?part_no=MPZ1005S121CT000"
			(at 276.86 107.95 0)
			(effects
				(font
					(size 1.27 1.27)
					(thickness 0.15)
				)
				(justify left bottom)
				(hide yes)
			)
		)
		(property "Description" "Ferrite Bead, 0402 [1005 Metric], 120 ohm, 1.2A, MPZ, 0.06 ohm, ± 25%, DC Power line"
			(at 290.83 118.11 0)
			(effects
				(font
					(size 1.27 1.27)
				)
				(hide yes)
			)
		)
		(property "Val" "120Z/1.2A"
			(at 288.3281 114.3 0)
			(effects
				(font
					(size 1.27 1.27)
				)
			)
		)
		(property "MPN" "MPZ1005S121CT000"
			(at 276.86 105.41 0)
			(effects
				(font
					(size 1.27 1.27)
					(thickness 0.15)
				)
				(justify left bottom)
				(hide yes)
			)
		)
		(property "Manufacturer" "TDK"
			(at 276.86 102.87 0)
			(effects
				(font
					(size 1.27 1.27)
					(thickness 0.15)
				)
				(justify left bottom)
				(hide yes)
			)
		)
		(property "Current" ""
			(at 270.51 95.25 0)
			(effects
				(font
					(size 1.27 1.27)
					(thickness 0.15)
				)
				(justify left bottom)
				(hide yes)
			)
		)
		(property "Author" "Antmicro"
			(at 276.86 100.33 0)
			(effects
				(font
					(size 1.27 1.27)
					(thickness 0.15)
				)
				(justify left bottom)
				(hide yes)
			)
		)
		(property "License" "Apache-2.0"
			(at 276.86 97.79 0)
			(effects
				(font
					(size 1.27 1.27)
					(thickness 0.15)
				)
				(justify left bottom)
				(hide yes)
			)
		)
		(property "Public" ""
			(at 270.51 102.87 0)
			(effects
				(font
					(size 1.27 1.27)
				)
				(justify left bottom)
				(hide yes)
			)
		)
		(pin "1"
		)
		(pin "2"
		)
		(instances
			(project "polarfire-som"
				(path ""
					(reference "FB6")
					(unit 1)
				)
			)
		)
	)
	(symbol
		(lib_id "antmicropower:PWR_FLAG")
		(at 260.35 135.89 270)
		(unit 1)
		(exclude_from_sim no)
		(in_bom yes)
		(on_board yes)
		(dnp no)
		(property "Reference" "#FLG05"
			(at 262.255 135.89 0)
			(effects
				(font
					(size 1.27 1.27)
				)
				(hide yes)
			)
		)
		(property "Value" "PWR_FLAG"
			(at 266.7 133.35 90)
			(effects
				(font
					(size 1.27 1.27)
				)
			)
		)
		(property "Footprint" ""
			(at 260.35 135.89 0)
			(effects
				(font
					(size 1.27 1.27)
				)
				(hide yes)
			)
		)
		(property "Datasheet" ""
			(at 260.35 135.89 0)
			(effects
				(font
					(size 1.27 1.27)
				)
				(hide yes)
			)
		)
		(property "Description" ""
			(at 260.35 135.89 0)
			(effects
				(font
					(size 1.27 1.27)
				)
				(hide yes)
			)
		)
		(pin "1"
		)
		(instances
			(project "polarfire-som"
				(path ""
					(reference "#FLG05")
					(unit 1)
				)
			)
		)
	)
	(symbol
		(lib_id "antmicroFPGAChips:CrossLink_LIF-MD6000-6JMG80I")
		(at 86.36 83.82 0)
		(unit 1)
		(exclude_from_sim no)
		(in_bom yes)
		(on_board yes)
		(dnp no)
		(fields_autoplaced yes)
		(property "Reference" "U16"
			(at 118.11 76.2 0)
			(effects
				(font
					(size 1.27 1.27)
					(thickness 0.15)
				)
			)
		)
		(property "Value" "CrossLink_LIF-MD6000-6JMG80I"
			(at 165.1 95.25 0)
			(effects
				(font
					(size 1.27 1.27)
					(thickness 0.15)
				)
				(justify left bottom)
				(hide yes)
			)
		)
		(property "Footprint" "antmicro-footprints:BGA-80_7x7mm_Layout10x10_P0.65mm"
			(at 165.1 97.79 0)
			(effects
				(font
					(size 1.27 1.27)
					(thickness 0.15)
				)
				(justify left bottom)
				(hide yes)
			)
		)
		(property "Datasheet" "https://www.latticesemi.com/view_document?document_id=51662"
			(at 165.1 100.33 0)
			(effects
				(font
					(size 1.27 1.27)
					(thickness 0.15)
				)
				(justify left bottom)
				(hide yes)
			)
		)
		(property "Description" "FPGA, CrossLink, PLL37 I/O, 400 MHz, 5936 Cells, 1.14 V to 1.26 V, CTFBGA-80"
			(at 86.36 83.82 0)
			(effects
				(font
					(size 1.27 1.27)
				)
				(hide yes)
			)
		)
		(property "MPN" "LIF-MD6000-6JMG80I"
			(at 118.11 78.74 0)
			(effects
				(font
					(size 1.27 1.27)
					(thickness 0.15)
				)
			)
		)
		(property "Manufacturer" "Lattice Semiconductor"
			(at 165.1 102.87 0)
			(effects
				(font
					(size 1.27 1.27)
					(thickness 0.15)
				)
				(justify left bottom)
				(hide yes)
			)
		)
		(property "Author" "Antmicro"
			(at 165.1 105.41 0)
			(effects
				(font
					(size 1.27 1.27)
					(thickness 0.15)
				)
				(justify left bottom)
				(hide yes)
			)
		)
		(property "License" "Apache-2.0"
			(at 165.1 107.95 0)
			(effects
				(font
					(size 1.27 1.27)
					(thickness 0.15)
				)
				(justify left bottom)
				(hide yes)
			)
		)
		(pin "A1"
		)
		(pin "A10"
		)
		(pin "A2"
		)
		(pin "A3"
		)
		(pin "A4"
		)
		(pin "A5"
		)
		(pin "A6"
		)
		(pin "A7"
		)
		(pin "A8"
		)
		(pin "A9"
		)
		(pin "B1"
		)
		(pin "B10"
		)
		(pin "B2"
		)
		(pin "B3"
		)
		(pin "B4"
		)
		(pin "B5"
		)
		(pin "B6"
		)
		(pin "B7"
		)
		(pin "B8"
		)
		(pin "B9"
		)
		(pin "C1"
		)
		(pin "C10"
		)
		(pin "C2"
		)
		(pin "C9"
		)
		(pin "D1"
		)
		(pin "D10"
		)
		(pin "D2"
		)
		(pin "D4"
		)
		(pin "D5"
		)
		(pin "D6"
		)
		(pin "D7"
		)
		(pin "D9"
		)
		(pin "E1"
		)
		(pin "E10"
		)
		(pin "E2"
		)
		(pin "E4"
		)
		(pin "E5"
		)
		(pin "E6"
		)
		(pin "E7"
		)
		(pin "E9"
		)
		(pin "F1"
		)
		(pin "F10"
		)
		(pin "F2"
		)
		(pin "F4"
		)
		(pin "F5"
		)
		(pin "F6"
		)
		(pin "F7"
		)
		(pin "F9"
		)
		(pin "G1"
		)
		(pin "G10"
		)
		(pin "G2"
		)
		(pin "G4"
		)
		(pin "G5"
		)
		(pin "G6"
		)
		(pin "G7"
		)
		(pin "G9"
		)
		(pin "H1"
		)
		(pin "H10"
		)
		(pin "H2"
		)
		(pin "H9"
		)
		(pin "J1"
		)
		(pin "J10"
		)
		(pin "J2"
		)
		(pin "J3"
		)
		(pin "J4"
		)
		(pin "J5"
		)
		(pin "J6"
		)
		(pin "J7"
		)
		(pin "J8"
		)
		(pin "J9"
		)
		(pin "K1"
		)
		(pin "K10"
		)
		(pin "K2"
		)
		(pin "K3"
		)
		(pin "K4"
		)
		(pin "K5"
		)
		(pin "K6"
		)
		(pin "K7"
		)
		(pin "K8"
		)
		(pin "K9"
		)
		(instances
			(project "polarfire-som"
				(path ""
					(reference "U16")
					(unit 1)
				)
			)
		)
	)
	(symbol
		(lib_id "antmicroCapacitors0402:C_10u_10V_0402")
		(at 354.33 160.02 90)
		(unit 1)
		(exclude_from_sim no)
		(in_bom yes)
		(on_board yes)
		(dnp no)
		(property "Reference" "C249"
			(at 351.79 156.2036 90)
			(effects
				(font
					(size 1.27 1.27)
					(thickness 0.15)
				)
				(justify left)
			)
		)
		(property "Value" "C_10u_10V_0402"
			(at 364.49 139.7 0)
			(effects
				(font
					(size 1.27 1.27)
					(thickness 0.15)
				)
				(justify left bottom)
				(hide yes)
			)
		)
		(property "Footprint" "antmicro-footprints:C_0402_1005Metric"
			(at 367.03 139.7 0)
			(effects
				(font
					(size 1.27 1.27)
					(thickness 0.15)
				)
				(justify left bottom)
				(hide yes)
			)
		)
		(property "Datasheet" "https://www.murata.com/products/productdetail?partno=GRM155R61A106ME11%23"
			(at 369.57 139.7 0)
			(effects
				(font
					(size 1.27 1.27)
					(thickness 0.15)
				)
				(justify left bottom)
				(hide yes)
			)
		)
		(property "Description" "Multilayer Ceramic Capacitors MLCC - SMD/SMT 10 uF 10 VDC 20% 0402 X5R"
			(at 354.33 160.02 0)
			(effects
				(font
					(size 1.27 1.27)
				)
				(hide yes)
			)
		)
		(property "MPN" "GRM155R61A106ME11D"
			(at 372.11 139.7 0)
			(effects
				(font
					(size 1.27 1.27)
					(thickness 0.15)
				)
				(justify left bottom)
				(hide yes)
			)
		)
		(property "Manufacturer" "Murata"
			(at 374.65 139.7 0)
			(effects
				(font
					(size 1.27 1.27)
					(thickness 0.15)
				)
				(justify left bottom)
				(hide yes)
			)
		)
		(property "License" "Apache-2.0"
			(at 377.19 139.7 0)
			(effects
				(font
					(size 1.27 1.27)
					(thickness 0.15)
				)
				(justify left bottom)
				(hide yes)
			)
		)
		(property "Author" "Antmicro"
			(at 379.73 139.7 0)
			(effects
				(font
					(size 1.27 1.27)
					(thickness 0.15)
				)
				(justify left bottom)
				(hide yes)
			)
		)
		(property "Val" "10u"
			(at 351.79 158.7436 90)
			(effects
				(font
					(size 1.27 1.27)
					(thickness 0.15)
				)
				(justify left)
			)
		)
		(property "Voltage" "10V"
			(at 382.27 139.7 0)
			(effects
				(font
					(size 1.27 1.27)
				)
				(justify left bottom)
				(hide yes)
			)
		)
		(property "Dielectric" "X5R"
			(at 384.81 139.7 0)
			(effects
				(font
					(size 1.27 1.27)
				)
				(justify left bottom)
				(hide yes)
			)
		)
		(property "Public" ""
			(at 387.35 139.7 0)
			(effects
				(font
					(size 1.27 1.27)
				)
				(justify left bottom)
				(hide yes)
			)
		)
		(pin "1"
		)
		(pin "2"
		)
		(instances
			(project "polarfire-som"
				(path ""
					(reference "C249")
					(unit 1)
				)
			)
		)
	)
	(symbol
		(lib_id "antmicroCapacitors0402:C_10u_10V_0402")
		(at 303.53 106.68 90)
		(unit 1)
		(exclude_from_sim no)
		(in_bom yes)
		(on_board yes)
		(dnp no)
		(property "Reference" "C201"
			(at 300.99 102.8636 90)
			(effects
				(font
					(size 1.27 1.27)
					(thickness 0.15)
				)
				(justify left)
			)
		)
		(property "Value" "C_10u_10V_0402"
			(at 313.69 86.36 0)
			(effects
				(font
					(size 1.27 1.27)
					(thickness 0.15)
				)
				(justify left bottom)
				(hide yes)
			)
		)
		(property "Footprint" "antmicro-footprints:C_0402_1005Metric"
			(at 316.23 86.36 0)
			(effects
				(font
					(size 1.27 1.27)
					(thickness 0.15)
				)
				(justify left bottom)
				(hide yes)
			)
		)
		(property "Datasheet" "https://www.murata.com/products/productdetail?partno=GRM155R61A106ME11%23"
			(at 318.77 86.36 0)
			(effects
				(font
					(size 1.27 1.27)
					(thickness 0.15)
				)
				(justify left bottom)
				(hide yes)
			)
		)
		(property "Description" "Multilayer Ceramic Capacitors MLCC - SMD/SMT 10 uF 10 VDC 20% 0402 X5R"
			(at 303.53 106.68 0)
			(effects
				(font
					(size 1.27 1.27)
				)
				(hide yes)
			)
		)
		(property "MPN" "GRM155R61A106ME11D"
			(at 321.31 86.36 0)
			(effects
				(font
					(size 1.27 1.27)
					(thickness 0.15)
				)
				(justify left bottom)
				(hide yes)
			)
		)
		(property "Manufacturer" "Murata"
			(at 323.85 86.36 0)
			(effects
				(font
					(size 1.27 1.27)
					(thickness 0.15)
				)
				(justify left bottom)
				(hide yes)
			)
		)
		(property "License" "Apache-2.0"
			(at 326.39 86.36 0)
			(effects
				(font
					(size 1.27 1.27)
					(thickness 0.15)
				)
				(justify left bottom)
				(hide yes)
			)
		)
		(property "Author" "Antmicro"
			(at 328.93 86.36 0)
			(effects
				(font
					(size 1.27 1.27)
					(thickness 0.15)
				)
				(justify left bottom)
				(hide yes)
			)
		)
		(property "Val" "10u"
			(at 300.99 105.4036 90)
			(effects
				(font
					(size 1.27 1.27)
					(thickness 0.15)
				)
				(justify left)
			)
		)
		(property "Voltage" "10V"
			(at 331.47 86.36 0)
			(effects
				(font
					(size 1.27 1.27)
				)
				(justify left bottom)
				(hide yes)
			)
		)
		(property "Dielectric" "X5R"
			(at 334.01 86.36 0)
			(effects
				(font
					(size 1.27 1.27)
				)
				(justify left bottom)
				(hide yes)
			)
		)
		(property "Public" ""
			(at 336.55 86.36 0)
			(effects
				(font
					(size 1.27 1.27)
				)
				(justify left bottom)
				(hide yes)
			)
		)
		(pin "1"
		)
		(pin "2"
		)
		(instances
			(project "polarfire-som"
				(path ""
					(reference "C201")
					(unit 1)
				)
			)
		)
	)
	(symbol
		(lib_id "antmicropower:PWR_FLAG")
		(at 311.15 100.33 270)
		(unit 1)
		(exclude_from_sim no)
		(in_bom yes)
		(on_board yes)
		(dnp no)
		(property "Reference" "#FLG04"
			(at 313.055 100.33 0)
			(effects
				(font
					(size 1.27 1.27)
				)
				(hide yes)
			)
		)
		(property "Value" "PWR_FLAG"
			(at 318.77 100.33 90)
			(effects
				(font
					(size 1.27 1.27)
				)
			)
		)
		(property "Footprint" ""
			(at 311.15 100.33 0)
			(effects
				(font
					(size 1.27 1.27)
				)
				(hide yes)
			)
		)
		(property "Datasheet" ""
			(at 311.15 100.33 0)
			(effects
				(font
					(size 1.27 1.27)
				)
				(hide yes)
			)
		)
		(property "Description" ""
			(at 311.15 100.33 0)
			(effects
				(font
					(size 1.27 1.27)
				)
				(hide yes)
			)
		)
		(pin "1"
		)
		(instances
			(project "polarfire-som"
				(path ""
					(reference "#FLG04")
					(unit 1)
				)
			)
		)
	)
	(symbol
		(lib_id "antmicroTestPoints:TP_0.75mm_SMD")
		(at 81.28 86.36 180)
		(unit 1)
		(exclude_from_sim no)
		(in_bom no)
		(on_board yes)
		(dnp no)
		(property "Reference" "TP12"
			(at 74.93 86.36 0)
			(effects
				(font
					(size 1.27 1.27)
					(thickness 0.15)
				)
			)
		)
		(property "Value" "TP_0.75mm_SMD"
			(at 70.485 82.55 0)
			(effects
				(font
					(size 1.27 1.27)
					(thickness 0.15)
				)
				(justify left bottom)
				(hide yes)
			)
		)
		(property "Footprint" "antmicro-footprints:TP_SMD_0.75mm"
			(at 70.485 80.01 0)
			(effects
				(font
					(size 1.27 1.27)
					(thickness 0.15)
				)
				(justify left bottom)
				(hide yes)
			)
		)
		(property "Datasheet" ""
			(at 63.5 73.66 0)
			(effects
				(font
					(size 1.27 1.27)
					(thickness 0.15)
				)
				(justify left bottom)
				(hide yes)
			)
		)
		(property "Description" "SMT test point"
			(at 81.28 86.36 0)
			(effects
				(font
					(size 1.27 1.27)
				)
				(hide yes)
			)
		)
		(property "MPN" ""
			(at 70.485 74.93 0)
			(effects
				(font
					(size 1.27 1.27)
					(thickness 0.15)
				)
				(justify left bottom)
				(hide yes)
			)
		)
		(property "Manufacturer" ""
			(at 70.485 80.01 0)
			(effects
				(font
					(size 1.27 1.27)
					(thickness 0.15)
				)
				(justify left bottom)
				(hide yes)
			)
		)
		(property "Author" "Antmicro"
			(at 70.485 77.47 0)
			(effects
				(font
					(size 1.27 1.27)
					(thickness 0.15)
				)
				(justify left bottom)
				(hide yes)
			)
		)
		(property "License" "Apache-2.0"
			(at 70.485 74.93 0)
			(effects
				(font
					(size 1.27 1.27)
					(thickness 0.15)
				)
				(justify left bottom)
				(hide yes)
			)
		)
		(property "Public" "False"
			(at 71.12 72.39 0)
			(effects
				(font
					(size 1.27 1.27)
				)
				(justify left bottom)
				(hide yes)
			)
		)
		(pin "1"
		)
		(instances
			(project "polarfire-som"
				(path ""
					(reference "TP12")
					(unit 1)
				)
			)
		)
	)
	(symbol
		(lib_id "antmicropower:PWR_FLAG")
		(at 361.95 135.89 270)
		(unit 1)
		(exclude_from_sim no)
		(in_bom yes)
		(on_board yes)
		(dnp no)
		(property "Reference" "#FLG012"
			(at 363.855 135.89 0)
			(effects
				(font
					(size 1.27 1.27)
				)
				(hide yes)
			)
		)
		(property "Value" "PWR_FLAG"
			(at 369.57 135.89 90)
			(effects
				(font
					(size 1.27 1.27)
				)
			)
		)
		(property "Footprint" ""
			(at 361.95 135.89 0)
			(effects
				(font
					(size 1.27 1.27)
				)
				(hide yes)
			)
		)
		(property "Datasheet" ""
			(at 361.95 135.89 0)
			(effects
				(font
					(size 1.27 1.27)
				)
				(hide yes)
			)
		)
		(property "Description" ""
			(at 361.95 135.89 0)
			(effects
				(font
					(size 1.27 1.27)
				)
				(hide yes)
			)
		)
		(pin "1"
		)
		(instances
			(project "polarfire-som"
				(path ""
					(reference "#FLG012")
					(unit 1)
				)
			)
		)
	)
	(symbol
		(lib_id "antmicroFerriteBeadsandChips:FB_120Z_1.2A_TDK-MPZ_0402")
		(at 344.17 153.67 180)
		(unit 1)
		(exclude_from_sim no)
		(in_bom yes)
		(on_board yes)
		(dnp no)
		(fields_autoplaced yes)
		(property "Reference" "FB11"
			(at 341.6681 147.32 0)
			(effects
				(font
					(size 1.27 1.27)
					(thickness 0.15)
				)
			)
		)
		(property "Value" "FB_120Z_1.2A_TDK-MPZ_0402"
			(at 330.2 151.13 0)
			(effects
				(font
					(size 1.27 1.27)
					(thickness 0.15)
				)
				(justify left bottom)
				(hide yes)
			)
		)
		(property "Footprint" "antmicro-footprints:FB_0402_1005Metric"
			(at 330.2 146.05 0)
			(effects
				(font
					(size 1.27 1.27)
					(thickness 0.15)
				)
				(justify left bottom)
				(hide yes)
			)
		)
		(property "Datasheet" "https://product.tdk.com/en/search/emc/emc/beads/info?part_no=MPZ1005S121CT000"
			(at 330.2 143.51 0)
			(effects
				(font
					(size 1.27 1.27)
					(thickness 0.15)
				)
				(justify left bottom)
				(hide yes)
			)
		)
		(property "Description" "Ferrite Bead, 0402 [1005 Metric], 120 ohm, 1.2A, MPZ, 0.06 ohm, ± 25%, DC Power line"
			(at 344.17 153.67 0)
			(effects
				(font
					(size 1.27 1.27)
				)
				(hide yes)
			)
		)
		(property "Val" "120Z/1.2A"
			(at 341.6681 149.86 0)
			(effects
				(font
					(size 1.27 1.27)
				)
			)
		)
		(property "MPN" "MPZ1005S121CT000"
			(at 330.2 140.97 0)
			(effects
				(font
					(size 1.27 1.27)
					(thickness 0.15)
				)
				(justify left bottom)
				(hide yes)
			)
		)
		(property "Manufacturer" "TDK"
			(at 330.2 138.43 0)
			(effects
				(font
					(size 1.27 1.27)
					(thickness 0.15)
				)
				(justify left bottom)
				(hide yes)
			)
		)
		(property "Current" ""
			(at 323.85 130.81 0)
			(effects
				(font
					(size 1.27 1.27)
					(thickness 0.15)
				)
				(justify left bottom)
				(hide yes)
			)
		)
		(property "Author" "Antmicro"
			(at 330.2 135.89 0)
			(effects
				(font
					(size 1.27 1.27)
					(thickness 0.15)
				)
				(justify left bottom)
				(hide yes)
			)
		)
		(property "License" "Apache-2.0"
			(at 330.2 133.35 0)
			(effects
				(font
					(size 1.27 1.27)
					(thickness 0.15)
				)
				(justify left bottom)
				(hide yes)
			)
		)
		(property "Public" ""
			(at 323.85 138.43 0)
			(effects
				(font
					(size 1.27 1.27)
				)
				(justify left bottom)
				(hide yes)
			)
		)
		(pin "1"
		)
		(pin "2"
		)
		(instances
			(project "polarfire-som"
				(path ""
					(reference "FB11")
					(unit 1)
				)
			)
		)
	)
	(symbol
		(lib_id "antmicropower:+1V2")
		(at 335.28 135.89 90)
		(unit 1)
		(exclude_from_sim no)
		(in_bom yes)
		(on_board yes)
		(dnp no)
		(property "Reference" "#PWR078"
			(at 339.09 135.89 0)
			(effects
				(font
					(size 1.27 1.27)
				)
				(hide yes)
			)
		)
		(property "Value" "+1V2"
			(at 328.93 135.89 90)
			(effects
				(font
					(size 1.27 1.27)
				)
			)
		)
		(property "Footprint" ""
			(at 335.28 135.89 0)
			(effects
				(font
					(size 1.27 1.27)
				)
				(hide yes)
			)
		)
		(property "Datasheet" ""
			(at 335.28 135.89 0)
			(effects
				(font
					(size 1.27 1.27)
				)
				(hide yes)
			)
		)
		(property "Description" ""
			(at 335.28 135.89 0)
			(effects
				(font
					(size 1.27 1.27)
				)
				(hide yes)
			)
		)
		(pin "1"
		)
		(instances
			(project "polarfire-som"
				(path ""
					(reference "#PWR078")
					(unit 1)
				)
			)
		)
	)
	(symbol
		(lib_id "antmicroCapacitors0402:C_100n_0402")
		(at 309.88 106.68 90)
		(unit 1)
		(exclude_from_sim no)
		(in_bom yes)
		(on_board yes)
		(dnp no)
		(fields_autoplaced yes)
		(property "Reference" "C205"
			(at 312.42 102.8636 90)
			(effects
				(font
					(size 1.27 1.27)
					(thickness 0.15)
				)
				(justify right)
			)
		)
		(property "Value" "C_100n_0402"
			(at 320.04 86.36 0)
			(effects
				(font
					(size 1.27 1.27)
					(thickness 0.15)
				)
				(justify left bottom)
				(hide yes)
			)
		)
		(property "Footprint" "antmicro-footprints:C_0402_1005Metric"
			(at 322.58 86.36 0)
			(effects
				(font
					(size 1.27 1.27)
					(thickness 0.15)
				)
				(justify left bottom)
				(hide yes)
			)
		)
		(property "Datasheet" "https://www.murata.com/products/productdetail?partno=GRM155R61H104KE14%23"
			(at 325.12 86.36 0)
			(effects
				(font
					(size 1.27 1.27)
					(thickness 0.15)
				)
				(justify left bottom)
				(hide yes)
			)
		)
		(property "Description" "SMD Multilayer Ceramic Capacitor, 0.1 µF, 50 V, 0402 [1005 Metric], ± 10%, X5R, GRM Series"
			(at 309.88 106.68 0)
			(effects
				(font
					(size 1.27 1.27)
				)
				(hide yes)
			)
		)
		(property "MPN" "GRM155R61H104KE14D"
			(at 327.66 86.36 0)
			(effects
				(font
					(size 1.27 1.27)
					(thickness 0.15)
				)
				(justify left bottom)
				(hide yes)
			)
		)
		(property "Manufacturer" "Murata"
			(at 330.2 86.36 0)
			(effects
				(font
					(size 1.27 1.27)
					(thickness 0.15)
				)
				(justify left bottom)
				(hide yes)
			)
		)
		(property "License" "Apache-2.0"
			(at 332.74 86.36 0)
			(effects
				(font
					(size 1.27 1.27)
					(thickness 0.15)
				)
				(justify left bottom)
				(hide yes)
			)
		)
		(property "Author" "Antmicro"
			(at 335.28 86.36 0)
			(effects
				(font
					(size 1.27 1.27)
					(thickness 0.15)
				)
				(justify left bottom)
				(hide yes)
			)
		)
		(property "Val" "100n"
			(at 312.42 105.4036 90)
			(effects
				(font
					(size 1.27 1.27)
					(thickness 0.15)
				)
				(justify right)
			)
		)
		(property "Voltage" "50V"
			(at 337.82 86.36 0)
			(effects
				(font
					(size 1.27 1.27)
				)
				(justify left bottom)
				(hide yes)
			)
		)
		(property "Dielectric" "X5R"
			(at 340.36 86.36 0)
			(effects
				(font
					(size 1.27 1.27)
				)
				(justify left bottom)
				(hide yes)
			)
		)
		(property "Public" ""
			(at 342.9 86.36 0)
			(effects
				(font
					(size 1.27 1.27)
				)
				(justify left bottom)
				(hide yes)
			)
		)
		(pin "1"
		)
		(pin "2"
		)
		(instances
			(project "polarfire-som"
				(path ""
					(reference "C205")
					(unit 1)
				)
			)
		)
	)
	(symbol
		(lib_id "antmicropower:GND")
		(at 68.58 83.82 270)
		(unit 1)
		(exclude_from_sim no)
		(in_bom yes)
		(on_board yes)
		(dnp no)
		(property "Reference" "#PWR0174"
			(at 66.04 92.71 0)
			(effects
				(font
					(size 1.27 1.27)
					(thickness 0.15)
				)
				(justify left bottom)
				(hide yes)
			)
		)
		(property "Value" "GND"
			(at 64.77 83.82 0)
			(effects
				(font
					(size 1.27 1.27)
					(thickness 0.15)
				)
			)
		)
		(property "Footprint" ""
			(at 60.96 92.71 0)
			(effects
				(font
					(size 1.27 1.27)
					(thickness 0.15)
				)
				(justify left bottom)
				(hide yes)
			)
		)
		(property "Datasheet" ""
			(at 55.88 92.71 0)
			(effects
				(font
					(size 1.27 1.27)
					(thickness 0.15)
				)
				(justify left bottom)
				(hide yes)
			)
		)
		(property "Description" ""
			(at 68.58 83.82 0)
			(effects
				(font
					(size 1.27 1.27)
				)
				(hide yes)
			)
		)
		(property "Author" "Antmicro"
			(at 60.96 92.71 0)
			(effects
				(font
					(size 1.27 1.27)
					(thickness 0.15)
				)
				(justify left bottom)
				(hide yes)
			)
		)
		(property "License" "Apache-2.0"
			(at 58.42 92.71 0)
			(effects
				(font
					(size 1.27 1.27)
					(thickness 0.15)
				)
				(justify left bottom)
				(hide yes)
			)
		)
		(pin "1"
		)
		(instances
			(project "polarfire-som"
				(path ""
					(reference "#PWR0174")
					(unit 1)
				)
			)
		)
	)
	(symbol
		(lib_id "antmicroFerriteBeadsandChips:FB_120Z_1.2A_TDK-MPZ_0402")
		(at 290.83 100.33 180)
		(unit 1)
		(exclude_from_sim no)
		(in_bom yes)
		(on_board yes)
		(dnp no)
		(fields_autoplaced yes)
		(property "Reference" "FB5"
			(at 288.3281 93.98 0)
			(effects
				(font
					(size 1.27 1.27)
					(thickness 0.15)
				)
			)
		)
		(property "Value" "FB_120Z_1.2A_TDK-MPZ_0402"
			(at 276.86 97.79 0)
			(effects
				(font
					(size 1.27 1.27)
					(thickness 0.15)
				)
				(justify left bottom)
				(hide yes)
			)
		)
		(property "Footprint" "antmicro-footprints:FB_0402_1005Metric"
			(at 276.86 92.71 0)
			(effects
				(font
					(size 1.27 1.27)
					(thickness 0.15)
				)
				(justify left bottom)
				(hide yes)
			)
		)
		(property "Datasheet" "https://product.tdk.com/en/search/emc/emc/beads/info?part_no=MPZ1005S121CT000"
			(at 276.86 90.17 0)
			(effects
				(font
					(size 1.27 1.27)
					(thickness 0.15)
				)
				(justify left bottom)
				(hide yes)
			)
		)
		(property "Description" "Ferrite Bead, 0402 [1005 Metric], 120 ohm, 1.2A, MPZ, 0.06 ohm, ± 25%, DC Power line"
			(at 290.83 100.33 0)
			(effects
				(font
					(size 1.27 1.27)
				)
				(hide yes)
			)
		)
		(property "Val" "120Z/1.2A"
			(at 288.3281 96.52 0)
			(effects
				(font
					(size 1.27 1.27)
				)
			)
		)
		(property "MPN" "MPZ1005S121CT000"
			(at 276.86 87.63 0)
			(effects
				(font
					(size 1.27 1.27)
					(thickness 0.15)
				)
				(justify left bottom)
				(hide yes)
			)
		)
		(property "Manufacturer" "TDK"
			(at 276.86 85.09 0)
			(effects
				(font
					(size 1.27 1.27)
					(thickness 0.15)
				)
				(justify left bottom)
				(hide yes)
			)
		)
		(property "Current" ""
			(at 270.51 77.47 0)
			(effects
				(font
					(size 1.27 1.27)
					(thickness 0.15)
				)
				(justify left bottom)
				(hide yes)
			)
		)
		(property "Author" "Antmicro"
			(at 276.86 82.55 0)
			(effects
				(font
					(size 1.27 1.27)
					(thickness 0.15)
				)
				(justify left bottom)
				(hide yes)
			)
		)
		(property "License" "Apache-2.0"
			(at 276.86 80.01 0)
			(effects
				(font
					(size 1.27 1.27)
					(thickness 0.15)
				)
				(justify left bottom)
				(hide yes)
			)
		)
		(property "Public" ""
			(at 270.51 85.09 0)
			(effects
				(font
					(size 1.27 1.27)
				)
				(justify left bottom)
				(hide yes)
			)
		)
		(pin "1"
		)
		(pin "2"
		)
		(instances
			(project "polarfire-som"
				(path ""
					(reference "FB5")
					(unit 1)
				)
			)
		)
	)
	(symbol
		(lib_id "antmicroCapacitors0402:C_100n_0402")
		(at 360.68 124.46 90)
		(unit 1)
		(exclude_from_sim no)
		(in_bom yes)
		(on_board yes)
		(dnp no)
		(property "Reference" "C212"
			(at 363.22 120.6435 90)
			(effects
				(font
					(size 1.27 1.27)
					(thickness 0.15)
				)
				(justify right)
			)
		)
		(property "Value" "C_100n_0402"
			(at 370.84 104.14 0)
			(effects
				(font
					(size 1.27 1.27)
					(thickness 0.15)
				)
				(justify left bottom)
				(hide yes)
			)
		)
		(property "Footprint" "antmicro-footprints:C_0402_1005Metric"
			(at 373.38 104.14 0)
			(effects
				(font
					(size 1.27 1.27)
					(thickness 0.15)
				)
				(justify left bottom)
				(hide yes)
			)
		)
		(property "Datasheet" "https://www.murata.com/products/productdetail?partno=GRM155R61H104KE14%23"
			(at 375.92 104.14 0)
			(effects
				(font
					(size 1.27 1.27)
					(thickness 0.15)
				)
				(justify left bottom)
				(hide yes)
			)
		)
		(property "Description" "SMD Multilayer Ceramic Capacitor, 0.1 µF, 50 V, 0402 [1005 Metric], ± 10%, X5R, GRM Series"
			(at 360.68 124.46 0)
			(effects
				(font
					(size 1.27 1.27)
				)
				(hide yes)
			)
		)
		(property "MPN" "GRM155R61H104KE14D"
			(at 378.46 104.14 0)
			(effects
				(font
					(size 1.27 1.27)
					(thickness 0.15)
				)
				(justify left bottom)
				(hide yes)
			)
		)
		(property "Manufacturer" "Murata"
			(at 381 104.14 0)
			(effects
				(font
					(size 1.27 1.27)
					(thickness 0.15)
				)
				(justify left bottom)
				(hide yes)
			)
		)
		(property "License" "Apache-2.0"
			(at 383.54 104.14 0)
			(effects
				(font
					(size 1.27 1.27)
					(thickness 0.15)
				)
				(justify left bottom)
				(hide yes)
			)
		)
		(property "Author" "Antmicro"
			(at 386.08 104.14 0)
			(effects
				(font
					(size 1.27 1.27)
					(thickness 0.15)
				)
				(justify left bottom)
				(hide yes)
			)
		)
		(property "Val" "100n"
			(at 368.3 123.19 90)
			(effects
				(font
					(size 1.27 1.27)
					(thickness 0.15)
				)
				(justify left bottom)
			)
		)
		(property "Voltage" "50V"
			(at 388.62 104.14 0)
			(effects
				(font
					(size 1.27 1.27)
				)
				(justify left bottom)
				(hide yes)
			)
		)
		(property "Dielectric" "X5R"
			(at 391.16 104.14 0)
			(effects
				(font
					(size 1.27 1.27)
				)
				(justify left bottom)
				(hide yes)
			)
		)
		(property "Public" ""
			(at 393.7 104.14 0)
			(effects
				(font
					(size 1.27 1.27)
				)
				(justify left bottom)
				(hide yes)
			)
		)
		(pin "1"
		)
		(pin "2"
		)
		(instances
			(project "polarfire-som"
				(path ""
					(reference "C212")
					(unit 1)
				)
			)
		)
	)
	(symbol
		(lib_id "antmicropower:PWR_FLAG")
		(at 311.15 118.11 270)
		(unit 1)
		(exclude_from_sim no)
		(in_bom yes)
		(on_board yes)
		(dnp no)
		(property "Reference" "#FLG018"
			(at 313.055 118.11 0)
			(effects
				(font
					(size 1.27 1.27)
				)
				(hide yes)
			)
		)
		(property "Value" "PWR_FLAG"
			(at 318.77 118.11 90)
			(effects
				(font
					(size 1.27 1.27)
				)
			)
		)
		(property "Footprint" ""
			(at 311.15 118.11 0)
			(effects
				(font
					(size 1.27 1.27)
				)
				(hide yes)
			)
		)
		(property "Datasheet" ""
			(at 311.15 118.11 0)
			(effects
				(font
					(size 1.27 1.27)
				)
				(hide yes)
			)
		)
		(property "Description" ""
			(at 311.15 118.11 0)
			(effects
				(font
					(size 1.27 1.27)
				)
				(hide yes)
			)
		)
		(pin "1"
		)
		(instances
			(project "polarfire-som"
				(path ""
					(reference "#FLG018")
					(unit 1)
				)
			)
		)
	)
	(symbol
		(lib_id "antmicropower:GND")
		(at 260.35 143.51 0)
		(unit 1)
		(exclude_from_sim no)
		(in_bom yes)
		(on_board yes)
		(dnp no)
		(property "Reference" "#PWR0189"
			(at 269.24 146.05 0)
			(effects
				(font
					(size 1.27 1.27)
					(thickness 0.15)
				)
				(justify left bottom)
				(hide yes)
			)
		)
		(property "Value" "GND"
			(at 260.35 147.32 0)
			(effects
				(font
					(size 1.27 1.27)
					(thickness 0.15)
				)
			)
		)
		(property "Footprint" ""
			(at 269.24 151.13 0)
			(effects
				(font
					(size 1.27 1.27)
					(thickness 0.15)
				)
				(justify left bottom)
				(hide yes)
			)
		)
		(property "Datasheet" ""
			(at 269.24 156.21 0)
			(effects
				(font
					(size 1.27 1.27)
					(thickness 0.15)
				)
				(justify left bottom)
				(hide yes)
			)
		)
		(property "Description" ""
			(at 260.35 143.51 0)
			(effects
				(font
					(size 1.27 1.27)
				)
				(hide yes)
			)
		)
		(property "Author" "Antmicro"
			(at 269.24 151.13 0)
			(effects
				(font
					(size 1.27 1.27)
					(thickness 0.15)
				)
				(justify left bottom)
				(hide yes)
			)
		)
		(property "License" "Apache-2.0"
			(at 269.24 153.67 0)
			(effects
				(font
					(size 1.27 1.27)
					(thickness 0.15)
				)
				(justify left bottom)
				(hide yes)
			)
		)
		(pin "1"
		)
		(instances
			(project "polarfire-som"
				(path ""
					(reference "#PWR0189")
					(unit 1)
				)
			)
		)
	)
	(symbol
		(lib_id "antmicroCapacitors0402:C_100n_0402")
		(at 360.68 106.68 90)
		(unit 1)
		(exclude_from_sim no)
		(in_bom yes)
		(on_board yes)
		(dnp no)
		(property "Reference" "C211"
			(at 363.22 102.8635 90)
			(effects
				(font
					(size 1.27 1.27)
					(thickness 0.15)
				)
				(justify right)
			)
		)
		(property "Value" "C_100n_0402"
			(at 370.84 86.36 0)
			(effects
				(font
					(size 1.27 1.27)
					(thickness 0.15)
				)
				(justify left bottom)
				(hide yes)
			)
		)
		(property "Footprint" "antmicro-footprints:C_0402_1005Metric"
			(at 373.38 86.36 0)
			(effects
				(font
					(size 1.27 1.27)
					(thickness 0.15)
				)
				(justify left bottom)
				(hide yes)
			)
		)
		(property "Datasheet" "https://www.murata.com/products/productdetail?partno=GRM155R61H104KE14%23"
			(at 375.92 86.36 0)
			(effects
				(font
					(size 1.27 1.27)
					(thickness 0.15)
				)
				(justify left bottom)
				(hide yes)
			)
		)
		(property "Description" "SMD Multilayer Ceramic Capacitor, 0.1 µF, 50 V, 0402 [1005 Metric], ± 10%, X5R, GRM Series"
			(at 360.68 106.68 0)
			(effects
				(font
					(size 1.27 1.27)
				)
				(hide yes)
			)
		)
		(property "MPN" "GRM155R61H104KE14D"
			(at 378.46 86.36 0)
			(effects
				(font
					(size 1.27 1.27)
					(thickness 0.15)
				)
				(justify left bottom)
				(hide yes)
			)
		)
		(property "Manufacturer" "Murata"
			(at 381 86.36 0)
			(effects
				(font
					(size 1.27 1.27)
					(thickness 0.15)
				)
				(justify left bottom)
				(hide yes)
			)
		)
		(property "License" "Apache-2.0"
			(at 383.54 86.36 0)
			(effects
				(font
					(size 1.27 1.27)
					(thickness 0.15)
				)
				(justify left bottom)
				(hide yes)
			)
		)
		(property "Author" "Antmicro"
			(at 386.08 86.36 0)
			(effects
				(font
					(size 1.27 1.27)
					(thickness 0.15)
				)
				(justify left bottom)
				(hide yes)
			)
		)
		(property "Val" "100n"
			(at 368.3 105.41 90)
			(effects
				(font
					(size 1.27 1.27)
					(thickness 0.15)
				)
				(justify left bottom)
			)
		)
		(property "Voltage" "50V"
			(at 388.62 86.36 0)
			(effects
				(font
					(size 1.27 1.27)
				)
				(justify left bottom)
				(hide yes)
			)
		)
		(property "Dielectric" "X5R"
			(at 391.16 86.36 0)
			(effects
				(font
					(size 1.27 1.27)
				)
				(justify left bottom)
				(hide yes)
			)
		)
		(property "Public" ""
			(at 393.7 86.36 0)
			(effects
				(font
					(size 1.27 1.27)
				)
				(justify left bottom)
				(hide yes)
			)
		)
		(pin "1"
		)
		(pin "2"
		)
		(instances
			(project "polarfire-som"
				(path ""
					(reference "C211")
					(unit 1)
				)
			)
		)
	)
	(symbol
		(lib_id "antmicropower:GND")
		(at 172.72 125.73 0)
		(unit 1)
		(exclude_from_sim no)
		(in_bom yes)
		(on_board yes)
		(dnp no)
		(property "Reference" "#PWR0176"
			(at 181.61 128.27 0)
			(effects
				(font
					(size 1.27 1.27)
					(thickness 0.15)
				)
				(justify left bottom)
				(hide yes)
			)
		)
		(property "Value" "GND"
			(at 172.72 129.54 0)
			(effects
				(font
					(size 1.27 1.27)
					(thickness 0.15)
				)
			)
		)
		(property "Footprint" ""
			(at 181.61 133.35 0)
			(effects
				(font
					(size 1.27 1.27)
					(thickness 0.15)
				)
				(justify left bottom)
				(hide yes)
			)
		)
		(property "Datasheet" ""
			(at 181.61 138.43 0)
			(effects
				(font
					(size 1.27 1.27)
					(thickness 0.15)
				)
				(justify left bottom)
				(hide yes)
			)
		)
		(property "Description" ""
			(at 172.72 125.73 0)
			(effects
				(font
					(size 1.27 1.27)
				)
				(hide yes)
			)
		)
		(property "Author" "Antmicro"
			(at 181.61 133.35 0)
			(effects
				(font
					(size 1.27 1.27)
					(thickness 0.15)
				)
				(justify left bottom)
				(hide yes)
			)
		)
		(property "License" "Apache-2.0"
			(at 181.61 135.89 0)
			(effects
				(font
					(size 1.27 1.27)
					(thickness 0.15)
				)
				(justify left bottom)
				(hide yes)
			)
		)
		(pin "1"
		)
		(instances
			(project "polarfire-som"
				(path ""
					(reference "#PWR0176")
					(unit 1)
				)
			)
		)
	)
	(symbol
		(lib_id "antmicropower:+1V2")
		(at 335.28 153.67 90)
		(unit 1)
		(exclude_from_sim no)
		(in_bom yes)
		(on_board yes)
		(dnp no)
		(property "Reference" "#PWR080"
			(at 339.09 153.67 0)
			(effects
				(font
					(size 1.27 1.27)
				)
				(hide yes)
			)
		)
		(property "Value" "+1V2"
			(at 328.93 153.67 90)
			(effects
				(font
					(size 1.27 1.27)
				)
			)
		)
		(property "Footprint" ""
			(at 335.28 153.67 0)
			(effects
				(font
					(size 1.27 1.27)
				)
				(hide yes)
			)
		)
		(property "Datasheet" ""
			(at 335.28 153.67 0)
			(effects
				(font
					(size 1.27 1.27)
				)
				(hide yes)
			)
		)
		(property "Description" ""
			(at 335.28 153.67 0)
			(effects
				(font
					(size 1.27 1.27)
				)
				(hide yes)
			)
		)
		(pin "1"
		)
		(instances
			(project "polarfire-som"
				(path ""
					(reference "#PWR080")
					(unit 1)
				)
			)
		)
	)
	(symbol
		(lib_id "antmicropower:PWR_FLAG")
		(at 261.62 118.11 270)
		(unit 1)
		(exclude_from_sim no)
		(in_bom yes)
		(on_board yes)
		(dnp no)
		(property "Reference" "#FLG019"
			(at 263.525 118.11 0)
			(effects
				(font
					(size 1.27 1.27)
				)
				(hide yes)
			)
		)
		(property "Value" "PWR_FLAG"
			(at 265.43 115.57 90)
			(effects
				(font
					(size 1.27 1.27)
				)
			)
		)
		(property "Footprint" ""
			(at 261.62 118.11 0)
			(effects
				(font
					(size 1.27 1.27)
				)
				(hide yes)
			)
		)
		(property "Datasheet" ""
			(at 261.62 118.11 0)
			(effects
				(font
					(size 1.27 1.27)
				)
				(hide yes)
			)
		)
		(property "Description" ""
			(at 261.62 118.11 0)
			(effects
				(font
					(size 1.27 1.27)
				)
				(hide yes)
			)
		)
		(pin "1"
		)
		(instances
			(project "polarfire-som"
				(path ""
					(reference "#FLG019")
					(unit 1)
				)
			)
		)
	)
	(symbol
		(lib_id "antmicropower:GND")
		(at 260.35 127 0)
		(unit 1)
		(exclude_from_sim no)
		(in_bom yes)
		(on_board yes)
		(dnp no)
		(property "Reference" "#PWR0188"
			(at 269.24 129.54 0)
			(effects
				(font
					(size 1.27 1.27)
					(thickness 0.15)
				)
				(justify left bottom)
				(hide yes)
			)
		)
		(property "Value" "GND"
			(at 260.35 130.81 0)
			(effects
				(font
					(size 1.27 1.27)
					(thickness 0.15)
				)
			)
		)
		(property "Footprint" ""
			(at 269.24 134.62 0)
			(effects
				(font
					(size 1.27 1.27)
					(thickness 0.15)
				)
				(justify left bottom)
				(hide yes)
			)
		)
		(property "Datasheet" ""
			(at 269.24 139.7 0)
			(effects
				(font
					(size 1.27 1.27)
					(thickness 0.15)
				)
				(justify left bottom)
				(hide yes)
			)
		)
		(property "Description" ""
			(at 260.35 127 0)
			(effects
				(font
					(size 1.27 1.27)
				)
				(hide yes)
			)
		)
		(property "Author" "Antmicro"
			(at 269.24 134.62 0)
			(effects
				(font
					(size 1.27 1.27)
					(thickness 0.15)
				)
				(justify left bottom)
				(hide yes)
			)
		)
		(property "License" "Apache-2.0"
			(at 269.24 137.16 0)
			(effects
				(font
					(size 1.27 1.27)
					(thickness 0.15)
				)
				(justify left bottom)
				(hide yes)
			)
		)
		(pin "1"
		)
		(instances
			(project "polarfire-som"
				(path ""
					(reference "#PWR0188")
					(unit 1)
				)
			)
		)
	)
	(symbol
		(lib_id "antmicropower:+1V2")
		(at 335.28 100.33 90)
		(unit 1)
		(exclude_from_sim no)
		(in_bom yes)
		(on_board yes)
		(dnp no)
		(property "Reference" "#PWR082"
			(at 339.09 100.33 0)
			(effects
				(font
					(size 1.27 1.27)
				)
				(hide yes)
			)
		)
		(property "Value" "+1V2"
			(at 328.93 100.33 90)
			(effects
				(font
					(size 1.27 1.27)
				)
			)
		)
		(property "Footprint" ""
			(at 335.28 100.33 0)
			(effects
				(font
					(size 1.27 1.27)
				)
				(hide yes)
			)
		)
		(property "Datasheet" ""
			(at 335.28 100.33 0)
			(effects
				(font
					(size 1.27 1.27)
				)
				(hide yes)
			)
		)
		(property "Description" ""
			(at 335.28 100.33 0)
			(effects
				(font
					(size 1.27 1.27)
				)
				(hide yes)
			)
		)
		(pin "1"
		)
		(instances
			(project "polarfire-som"
				(path ""
					(reference "#PWR082")
					(unit 1)
				)
			)
		)
	)
	(symbol
		(lib_id "antmicropower:GND")
		(at 260.35 109.22 0)
		(unit 1)
		(exclude_from_sim no)
		(in_bom yes)
		(on_board yes)
		(dnp no)
		(property "Reference" "#PWR0187"
			(at 269.24 111.76 0)
			(effects
				(font
					(size 1.27 1.27)
					(thickness 0.15)
				)
				(justify left bottom)
				(hide yes)
			)
		)
		(property "Value" "GND"
			(at 260.35 113.03 0)
			(effects
				(font
					(size 1.27 1.27)
					(thickness 0.15)
				)
			)
		)
		(property "Footprint" ""
			(at 269.24 116.84 0)
			(effects
				(font
					(size 1.27 1.27)
					(thickness 0.15)
				)
				(justify left bottom)
				(hide yes)
			)
		)
		(property "Datasheet" ""
			(at 269.24 121.92 0)
			(effects
				(font
					(size 1.27 1.27)
					(thickness 0.15)
				)
				(justify left bottom)
				(hide yes)
			)
		)
		(property "Description" ""
			(at 260.35 109.22 0)
			(effects
				(font
					(size 1.27 1.27)
				)
				(hide yes)
			)
		)
		(property "Author" "Antmicro"
			(at 269.24 116.84 0)
			(effects
				(font
					(size 1.27 1.27)
					(thickness 0.15)
				)
				(justify left bottom)
				(hide yes)
			)
		)
		(property "License" "Apache-2.0"
			(at 269.24 119.38 0)
			(effects
				(font
					(size 1.27 1.27)
					(thickness 0.15)
				)
				(justify left bottom)
				(hide yes)
			)
		)
		(pin "1"
		)
		(instances
			(project "polarfire-som"
				(path ""
					(reference "#PWR0187")
					(unit 1)
				)
			)
		)
	)
	(symbol
		(lib_id "antmicroCapacitors0402:C_100n_0402")
		(at 360.68 142.24 90)
		(unit 1)
		(exclude_from_sim no)
		(in_bom yes)
		(on_board yes)
		(dnp no)
		(property "Reference" "C280"
			(at 363.22 138.4235 90)
			(effects
				(font
					(size 1.27 1.27)
					(thickness 0.15)
				)
				(justify right)
			)
		)
		(property "Value" "C_100n_0402"
			(at 370.84 121.92 0)
			(effects
				(font
					(size 1.27 1.27)
					(thickness 0.15)
				)
				(justify left bottom)
				(hide yes)
			)
		)
		(property "Footprint" "antmicro-footprints:C_0402_1005Metric"
			(at 373.38 121.92 0)
			(effects
				(font
					(size 1.27 1.27)
					(thickness 0.15)
				)
				(justify left bottom)
				(hide yes)
			)
		)
		(property "Datasheet" "https://www.murata.com/products/productdetail?partno=GRM155R61H104KE14%23"
			(at 375.92 121.92 0)
			(effects
				(font
					(size 1.27 1.27)
					(thickness 0.15)
				)
				(justify left bottom)
				(hide yes)
			)
		)
		(property "Description" "SMD Multilayer Ceramic Capacitor, 0.1 µF, 50 V, 0402 [1005 Metric], ± 10%, X5R, GRM Series"
			(at 360.68 142.24 0)
			(effects
				(font
					(size 1.27 1.27)
				)
				(hide yes)
			)
		)
		(property "MPN" "GRM155R61H104KE14D"
			(at 378.46 121.92 0)
			(effects
				(font
					(size 1.27 1.27)
					(thickness 0.15)
				)
				(justify left bottom)
				(hide yes)
			)
		)
		(property "Manufacturer" "Murata"
			(at 381 121.92 0)
			(effects
				(font
					(size 1.27 1.27)
					(thickness 0.15)
				)
				(justify left bottom)
				(hide yes)
			)
		)
		(property "License" "Apache-2.0"
			(at 383.54 121.92 0)
			(effects
				(font
					(size 1.27 1.27)
					(thickness 0.15)
				)
				(justify left bottom)
				(hide yes)
			)
		)
		(property "Author" "Antmicro"
			(at 386.08 121.92 0)
			(effects
				(font
					(size 1.27 1.27)
					(thickness 0.15)
				)
				(justify left bottom)
				(hide yes)
			)
		)
		(property "Val" "100n"
			(at 368.3 140.97 90)
			(effects
				(font
					(size 1.27 1.27)
					(thickness 0.15)
				)
				(justify left bottom)
			)
		)
		(property "Voltage" "50V"
			(at 388.62 121.92 0)
			(effects
				(font
					(size 1.27 1.27)
				)
				(justify left bottom)
				(hide yes)
			)
		)
		(property "Dielectric" "X5R"
			(at 391.16 121.92 0)
			(effects
				(font
					(size 1.27 1.27)
				)
				(justify left bottom)
				(hide yes)
			)
		)
		(property "Public" ""
			(at 393.7 121.92 0)
			(effects
				(font
					(size 1.27 1.27)
				)
				(justify left bottom)
				(hide yes)
			)
		)
		(pin "1"
		)
		(pin "2"
		)
		(instances
			(project "polarfire-som"
				(path ""
					(reference "C280")
					(unit 1)
				)
			)
		)
	)
	(symbol
		(lib_id "antmicroFerriteBeadsandChips:FB_120Z_1.2A_TDK-MPZ_0402")
		(at 247.65 118.11 180)
		(unit 1)
		(exclude_from_sim no)
		(in_bom yes)
		(on_board yes)
		(dnp no)
		(property "Reference" "FB3"
			(at 245.1481 111.76 0)
			(effects
				(font
					(size 1.27 1.27)
					(thickness 0.15)
				)
			)
		)
		(property "Value" "FB_120Z_1.2A_TDK-MPZ_0402"
			(at 233.68 115.57 0)
			(effects
				(font
					(size 1.27 1.27)
					(thickness 0.15)
				)
				(justify left bottom)
				(hide yes)
			)
		)
		(property "Footprint" "antmicro-footprints:FB_0402_1005Metric"
			(at 233.68 110.49 0)
			(effects
				(font
					(size 1.27 1.27)
					(thickness 0.15)
				)
				(justify left bottom)
				(hide yes)
			)
		)
		(property "Datasheet" "https://product.tdk.com/en/search/emc/emc/beads/info?part_no=MPZ1005S121CT000"
			(at 233.68 107.95 0)
			(effects
				(font
					(size 1.27 1.27)
					(thickness 0.15)
				)
				(justify left bottom)
				(hide yes)
			)
		)
		(property "Description" "Ferrite Bead, 0402 [1005 Metric], 120 ohm, 1.2A, MPZ, 0.06 ohm, ± 25%, DC Power line"
			(at 247.65 118.11 0)
			(effects
				(font
					(size 1.27 1.27)
				)
				(hide yes)
			)
		)
		(property "Val" "120Z/1.2A"
			(at 245.1481 114.3 0)
			(effects
				(font
					(size 1.27 1.27)
				)
			)
		)
		(property "MPN" "MPZ1005S121CT000"
			(at 233.68 105.41 0)
			(effects
				(font
					(size 1.27 1.27)
					(thickness 0.15)
				)
				(justify left bottom)
				(hide yes)
			)
		)
		(property "Manufacturer" "TDK"
			(at 233.68 102.87 0)
			(effects
				(font
					(size 1.27 1.27)
					(thickness 0.15)
				)
				(justify left bottom)
				(hide yes)
			)
		)
		(property "Current" ""
			(at 227.33 95.25 0)
			(effects
				(font
					(size 1.27 1.27)
					(thickness 0.15)
				)
				(justify left bottom)
				(hide yes)
			)
		)
		(property "Author" "Antmicro"
			(at 233.68 100.33 0)
			(effects
				(font
					(size 1.27 1.27)
					(thickness 0.15)
				)
				(justify left bottom)
				(hide yes)
			)
		)
		(property "License" "Apache-2.0"
			(at 233.68 97.79 0)
			(effects
				(font
					(size 1.27 1.27)
					(thickness 0.15)
				)
				(justify left bottom)
				(hide yes)
			)
		)
		(property "Public" ""
			(at 227.33 102.87 0)
			(effects
				(font
					(size 1.27 1.27)
				)
				(justify left bottom)
				(hide yes)
			)
		)
		(pin "1"
		)
		(pin "2"
		)
		(instances
			(project "polarfire-som"
				(path ""
					(reference "FB3")
					(unit 1)
				)
			)
		)
	)
	(symbol
		(lib_id "antmicropower:GND")
		(at 153.67 191.77 0)
		(unit 1)
		(exclude_from_sim no)
		(in_bom yes)
		(on_board yes)
		(dnp no)
		(property "Reference" "#PWR0175"
			(at 162.56 194.31 0)
			(effects
				(font
					(size 1.27 1.27)
					(thickness 0.15)
				)
				(justify left bottom)
				(hide yes)
			)
		)
		(property "Value" "GND"
			(at 153.67 195.58 0)
			(effects
				(font
					(size 1.27 1.27)
					(thickness 0.15)
				)
			)
		)
		(property "Footprint" ""
			(at 162.56 199.39 0)
			(effects
				(font
					(size 1.27 1.27)
					(thickness 0.15)
				)
				(justify left bottom)
				(hide yes)
			)
		)
		(property "Datasheet" ""
			(at 162.56 204.47 0)
			(effects
				(font
					(size 1.27 1.27)
					(thickness 0.15)
				)
				(justify left bottom)
				(hide yes)
			)
		)
		(property "Description" ""
			(at 153.67 191.77 0)
			(effects
				(font
					(size 1.27 1.27)
				)
				(hide yes)
			)
		)
		(property "Author" "Antmicro"
			(at 162.56 199.39 0)
			(effects
				(font
					(size 1.27 1.27)
					(thickness 0.15)
				)
				(justify left bottom)
				(hide yes)
			)
		)
		(property "License" "Apache-2.0"
			(at 162.56 201.93 0)
			(effects
				(font
					(size 1.27 1.27)
					(thickness 0.15)
				)
				(justify left bottom)
				(hide yes)
			)
		)
		(pin "1"
		)
		(instances
			(project "polarfire-som"
				(path ""
					(reference "#PWR0175")
					(unit 1)
				)
			)
		)
	)
	(symbol
		(lib_id "antmicropower:PWR_FLAG")
		(at 361.95 100.33 270)
		(unit 1)
		(exclude_from_sim no)
		(in_bom yes)
		(on_board yes)
		(dnp no)
		(property "Reference" "#FLG010"
			(at 363.855 100.33 0)
			(effects
				(font
					(size 1.27 1.27)
				)
				(hide yes)
			)
		)
		(property "Value" "PWR_FLAG"
			(at 369.57 100.33 90)
			(effects
				(font
					(size 1.27 1.27)
				)
			)
		)
		(property "Footprint" ""
			(at 361.95 100.33 0)
			(effects
				(font
					(size 1.27 1.27)
				)
				(hide yes)
			)
		)
		(property "Datasheet" ""
			(at 361.95 100.33 0)
			(effects
				(font
					(size 1.27 1.27)
				)
				(hide yes)
			)
		)
		(property "Description" ""
			(at 361.95 100.33 0)
			(effects
				(font
					(size 1.27 1.27)
				)
				(hide yes)
			)
		)
		(pin "1"
		)
		(instances
			(project "polarfire-som"
				(path ""
					(reference "#FLG010")
					(unit 1)
				)
			)
		)
	)
	(symbol
		(lib_id "antmicroCapacitors0402:C_100n_0402")
		(at 260.35 124.46 90)
		(unit 1)
		(exclude_from_sim no)
		(in_bom yes)
		(on_board yes)
		(dnp no)
		(fields_autoplaced yes)
		(property "Reference" "C199"
			(at 262.89 120.6436 90)
			(effects
				(font
					(size 1.27 1.27)
					(thickness 0.15)
				)
				(justify right)
			)
		)
		(property "Value" "C_100n_0402"
			(at 270.51 104.14 0)
			(effects
				(font
					(size 1.27 1.27)
					(thickness 0.15)
				)
				(justify left bottom)
				(hide yes)
			)
		)
		(property "Footprint" "antmicro-footprints:C_0402_1005Metric"
			(at 273.05 104.14 0)
			(effects
				(font
					(size 1.27 1.27)
					(thickness 0.15)
				)
				(justify left bottom)
				(hide yes)
			)
		)
		(property "Datasheet" "https://www.murata.com/products/productdetail?partno=GRM155R61H104KE14%23"
			(at 275.59 104.14 0)
			(effects
				(font
					(size 1.27 1.27)
					(thickness 0.15)
				)
				(justify left bottom)
				(hide yes)
			)
		)
		(property "Description" "SMD Multilayer Ceramic Capacitor, 0.1 µF, 50 V, 0402 [1005 Metric], ± 10%, X5R, GRM Series"
			(at 260.35 124.46 0)
			(effects
				(font
					(size 1.27 1.27)
				)
				(hide yes)
			)
		)
		(property "MPN" "GRM155R61H104KE14D"
			(at 278.13 104.14 0)
			(effects
				(font
					(size 1.27 1.27)
					(thickness 0.15)
				)
				(justify left bottom)
				(hide yes)
			)
		)
		(property "Manufacturer" "Murata"
			(at 280.67 104.14 0)
			(effects
				(font
					(size 1.27 1.27)
					(thickness 0.15)
				)
				(justify left bottom)
				(hide yes)
			)
		)
		(property "License" "Apache-2.0"
			(at 283.21 104.14 0)
			(effects
				(font
					(size 1.27 1.27)
					(thickness 0.15)
				)
				(justify left bottom)
				(hide yes)
			)
		)
		(property "Author" "Antmicro"
			(at 285.75 104.14 0)
			(effects
				(font
					(size 1.27 1.27)
					(thickness 0.15)
				)
				(justify left bottom)
				(hide yes)
			)
		)
		(property "Val" "100n"
			(at 262.89 123.1836 90)
			(effects
				(font
					(size 1.27 1.27)
					(thickness 0.15)
				)
				(justify right)
			)
		)
		(property "Voltage" "50V"
			(at 288.29 104.14 0)
			(effects
				(font
					(size 1.27 1.27)
				)
				(justify left bottom)
				(hide yes)
			)
		)
		(property "Dielectric" "X5R"
			(at 290.83 104.14 0)
			(effects
				(font
					(size 1.27 1.27)
				)
				(justify left bottom)
				(hide yes)
			)
		)
		(property "Public" ""
			(at 293.37 104.14 0)
			(effects
				(font
					(size 1.27 1.27)
				)
				(justify left bottom)
				(hide yes)
			)
		)
		(pin "1"
		)
		(pin "2"
		)
		(instances
			(project "polarfire-som"
				(path ""
					(reference "C199")
					(unit 1)
				)
			)
		)
	)
	(symbol
		(lib_id "antmicroCapacitors0402:C_100n_0402")
		(at 303.53 142.24 90)
		(unit 1)
		(exclude_from_sim no)
		(in_bom yes)
		(on_board yes)
		(dnp no)
		(fields_autoplaced yes)
		(property "Reference" "C210"
			(at 306.07 138.4236 90)
			(effects
				(font
					(size 1.27 1.27)
					(thickness 0.15)
				)
				(justify right)
			)
		)
		(property "Value" "C_100n_0402"
			(at 313.69 121.92 0)
			(effects
				(font
					(size 1.27 1.27)
					(thickness 0.15)
				)
				(justify left bottom)
				(hide yes)
			)
		)
		(property "Footprint" "antmicro-footprints:C_0402_1005Metric"
			(at 316.23 121.92 0)
			(effects
				(font
					(size 1.27 1.27)
					(thickness 0.15)
				)
				(justify left bottom)
				(hide yes)
			)
		)
		(property "Datasheet" "https://www.murata.com/products/productdetail?partno=GRM155R61H104KE14%23"
			(at 318.77 121.92 0)
			(effects
				(font
					(size 1.27 1.27)
					(thickness 0.15)
				)
				(justify left bottom)
				(hide yes)
			)
		)
		(property "Description" "SMD Multilayer Ceramic Capacitor, 0.1 µF, 50 V, 0402 [1005 Metric], ± 10%, X5R, GRM Series"
			(at 303.53 142.24 0)
			(effects
				(font
					(size 1.27 1.27)
				)
				(hide yes)
			)
		)
		(property "MPN" "GRM155R61H104KE14D"
			(at 321.31 121.92 0)
			(effects
				(font
					(size 1.27 1.27)
					(thickness 0.15)
				)
				(justify left bottom)
				(hide yes)
			)
		)
		(property "Manufacturer" "Murata"
			(at 323.85 121.92 0)
			(effects
				(font
					(size 1.27 1.27)
					(thickness 0.15)
				)
				(justify left bottom)
				(hide yes)
			)
		)
		(property "License" "Apache-2.0"
			(at 326.39 121.92 0)
			(effects
				(font
					(size 1.27 1.27)
					(thickness 0.15)
				)
				(justify left bottom)
				(hide yes)
			)
		)
		(property "Author" "Antmicro"
			(at 328.93 121.92 0)
			(effects
				(font
					(size 1.27 1.27)
					(thickness 0.15)
				)
				(justify left bottom)
				(hide yes)
			)
		)
		(property "Val" "100n"
			(at 306.07 140.9636 90)
			(effects
				(font
					(size 1.27 1.27)
					(thickness 0.15)
				)
				(justify right)
			)
		)
		(property "Voltage" "50V"
			(at 331.47 121.92 0)
			(effects
				(font
					(size 1.27 1.27)
				)
				(justify left bottom)
				(hide yes)
			)
		)
		(property "Dielectric" "X5R"
			(at 334.01 121.92 0)
			(effects
				(font
					(size 1.27 1.27)
				)
				(justify left bottom)
				(hide yes)
			)
		)
		(property "Public" ""
			(at 336.55 121.92 0)
			(effects
				(font
					(size 1.27 1.27)
				)
				(justify left bottom)
				(hide yes)
			)
		)
		(pin "1"
		)
		(pin "2"
		)
		(instances
			(project "polarfire-som"
				(path ""
					(reference "C210")
					(unit 1)
				)
			)
		)
	)
	(symbol
		(lib_id "antmicroCapacitors0402:C_100n_0402")
		(at 360.68 160.02 90)
		(unit 1)
		(exclude_from_sim no)
		(in_bom yes)
		(on_board yes)
		(dnp no)
		(property "Reference" "C281"
			(at 363.22 156.2035 90)
			(effects
				(font
					(size 1.27 1.27)
					(thickness 0.15)
				)
				(justify right)
			)
		)
		(property "Value" "C_100n_0402"
			(at 370.84 139.7 0)
			(effects
				(font
					(size 1.27 1.27)
					(thickness 0.15)
				)
				(justify left bottom)
				(hide yes)
			)
		)
		(property "Footprint" "antmicro-footprints:C_0402_1005Metric"
			(at 373.38 139.7 0)
			(effects
				(font
					(size 1.27 1.27)
					(thickness 0.15)
				)
				(justify left bottom)
				(hide yes)
			)
		)
		(property "Datasheet" "https://www.murata.com/products/productdetail?partno=GRM155R61H104KE14%23"
			(at 375.92 139.7 0)
			(effects
				(font
					(size 1.27 1.27)
					(thickness 0.15)
				)
				(justify left bottom)
				(hide yes)
			)
		)
		(property "Description" "SMD Multilayer Ceramic Capacitor, 0.1 µF, 50 V, 0402 [1005 Metric], ± 10%, X5R, GRM Series"
			(at 360.68 160.02 0)
			(effects
				(font
					(size 1.27 1.27)
				)
				(hide yes)
			)
		)
		(property "MPN" "GRM155R61H104KE14D"
			(at 378.46 139.7 0)
			(effects
				(font
					(size 1.27 1.27)
					(thickness 0.15)
				)
				(justify left bottom)
				(hide yes)
			)
		)
		(property "Manufacturer" "Murata"
			(at 381 139.7 0)
			(effects
				(font
					(size 1.27 1.27)
					(thickness 0.15)
				)
				(justify left bottom)
				(hide yes)
			)
		)
		(property "License" "Apache-2.0"
			(at 383.54 139.7 0)
			(effects
				(font
					(size 1.27 1.27)
					(thickness 0.15)
				)
				(justify left bottom)
				(hide yes)
			)
		)
		(property "Author" "Antmicro"
			(at 386.08 139.7 0)
			(effects
				(font
					(size 1.27 1.27)
					(thickness 0.15)
				)
				(justify left bottom)
				(hide yes)
			)
		)
		(property "Val" "100n"
			(at 368.3 158.75 90)
			(effects
				(font
					(size 1.27 1.27)
					(thickness 0.15)
				)
				(justify left bottom)
			)
		)
		(property "Voltage" "50V"
			(at 388.62 139.7 0)
			(effects
				(font
					(size 1.27 1.27)
				)
				(justify left bottom)
				(hide yes)
			)
		)
		(property "Dielectric" "X5R"
			(at 391.16 139.7 0)
			(effects
				(font
					(size 1.27 1.27)
				)
				(justify left bottom)
				(hide yes)
			)
		)
		(property "Public" ""
			(at 393.7 139.7 0)
			(effects
				(font
					(size 1.27 1.27)
				)
				(justify left bottom)
				(hide yes)
			)
		)
		(pin "1"
		)
		(pin "2"
		)
		(instances
			(project "polarfire-som"
				(path ""
					(reference "C281")
					(unit 1)
				)
			)
		)
	)
	(symbol
		(lib_id "antmicroFerriteBeadsandChips:FB_120Z_1.2A_TDK-MPZ_0402")
		(at 247.65 100.33 180)
		(unit 1)
		(exclude_from_sim no)
		(in_bom yes)
		(on_board yes)
		(dnp no)
		(property "Reference" "FB2"
			(at 245.1481 93.98 0)
			(effects
				(font
					(size 1.27 1.27)
					(thickness 0.15)
				)
			)
		)
		(property "Value" "FB_120Z_1.2A_TDK-MPZ_0402"
			(at 233.68 97.79 0)
			(effects
				(font
					(size 1.27 1.27)
					(thickness 0.15)
				)
				(justify left bottom)
				(hide yes)
			)
		)
		(property "Footprint" "antmicro-footprints:FB_0402_1005Metric"
			(at 233.68 92.71 0)
			(effects
				(font
					(size 1.27 1.27)
					(thickness 0.15)
				)
				(justify left bottom)
				(hide yes)
			)
		)
		(property "Datasheet" "https://product.tdk.com/en/search/emc/emc/beads/info?part_no=MPZ1005S121CT000"
			(at 233.68 90.17 0)
			(effects
				(font
					(size 1.27 1.27)
					(thickness 0.15)
				)
				(justify left bottom)
				(hide yes)
			)
		)
		(property "Description" "Ferrite Bead, 0402 [1005 Metric], 120 ohm, 1.2A, MPZ, 0.06 ohm, ± 25%, DC Power line"
			(at 247.65 100.33 0)
			(effects
				(font
					(size 1.27 1.27)
				)
				(hide yes)
			)
		)
		(property "Val" "120Z/1.2A"
			(at 245.1481 96.52 0)
			(effects
				(font
					(size 1.27 1.27)
				)
			)
		)
		(property "MPN" "MPZ1005S121CT000"
			(at 233.68 87.63 0)
			(effects
				(font
					(size 1.27 1.27)
					(thickness 0.15)
				)
				(justify left bottom)
				(hide yes)
			)
		)
		(property "Manufacturer" "TDK"
			(at 233.68 85.09 0)
			(effects
				(font
					(size 1.27 1.27)
					(thickness 0.15)
				)
				(justify left bottom)
				(hide yes)
			)
		)
		(property "Current" ""
			(at 227.33 77.47 0)
			(effects
				(font
					(size 1.27 1.27)
					(thickness 0.15)
				)
				(justify left bottom)
				(hide yes)
			)
		)
		(property "Author" "Antmicro"
			(at 233.68 82.55 0)
			(effects
				(font
					(size 1.27 1.27)
					(thickness 0.15)
				)
				(justify left bottom)
				(hide yes)
			)
		)
		(property "License" "Apache-2.0"
			(at 233.68 80.01 0)
			(effects
				(font
					(size 1.27 1.27)
					(thickness 0.15)
				)
				(justify left bottom)
				(hide yes)
			)
		)
		(property "Public" ""
			(at 227.33 85.09 0)
			(effects
				(font
					(size 1.27 1.27)
				)
				(justify left bottom)
				(hide yes)
			)
		)
		(pin "1"
		)
		(pin "2"
		)
		(instances
			(project "polarfire-som"
				(path ""
					(reference "FB2")
					(unit 1)
				)
			)
		)
	)
	(symbol
		(lib_id "antmicropower:PWR_FLAG")
		(at 261.62 100.33 270)
		(unit 1)
		(exclude_from_sim no)
		(in_bom yes)
		(on_board yes)
		(dnp no)
		(property "Reference" "#FLG022"
			(at 263.525 100.33 0)
			(effects
				(font
					(size 1.27 1.27)
				)
				(hide yes)
			)
		)
		(property "Value" "PWR_FLAG"
			(at 265.43 97.79 90)
			(effects
				(font
					(size 1.27 1.27)
				)
			)
		)
		(property "Footprint" ""
			(at 261.62 100.33 0)
			(effects
				(font
					(size 1.27 1.27)
				)
				(hide yes)
			)
		)
		(property "Datasheet" ""
			(at 261.62 100.33 0)
			(effects
				(font
					(size 1.27 1.27)
				)
				(hide yes)
			)
		)
		(property "Description" ""
			(at 261.62 100.33 0)
			(effects
				(font
					(size 1.27 1.27)
				)
				(hide yes)
			)
		)
		(pin "1"
		)
		(instances
			(project "polarfire-som"
				(path ""
					(reference "#FLG022")
					(unit 1)
				)
			)
		)
	)
	(symbol
		(lib_id "antmicroFerriteBeadsandChips:FB_120Z_1.2A_TDK-MPZ_0402")
		(at 344.17 135.89 180)
		(unit 1)
		(exclude_from_sim no)
		(in_bom yes)
		(on_board yes)
		(dnp no)
		(fields_autoplaced yes)
		(property "Reference" "FB10"
			(at 341.6681 129.54 0)
			(effects
				(font
					(size 1.27 1.27)
					(thickness 0.15)
				)
			)
		)
		(property "Value" "FB_120Z_1.2A_TDK-MPZ_0402"
			(at 330.2 133.35 0)
			(effects
				(font
					(size 1.27 1.27)
					(thickness 0.15)
				)
				(justify left bottom)
				(hide yes)
			)
		)
		(property "Footprint" "antmicro-footprints:FB_0402_1005Metric"
			(at 330.2 128.27 0)
			(effects
				(font
					(size 1.27 1.27)
					(thickness 0.15)
				)
				(justify left bottom)
				(hide yes)
			)
		)
		(property "Datasheet" "https://product.tdk.com/en/search/emc/emc/beads/info?part_no=MPZ1005S121CT000"
			(at 330.2 125.73 0)
			(effects
				(font
					(size 1.27 1.27)
					(thickness 0.15)
				)
				(justify left bottom)
				(hide yes)
			)
		)
		(property "Description" "Ferrite Bead, 0402 [1005 Metric], 120 ohm, 1.2A, MPZ, 0.06 ohm, ± 25%, DC Power line"
			(at 344.17 135.89 0)
			(effects
				(font
					(size 1.27 1.27)
				)
				(hide yes)
			)
		)
		(property "Val" "120Z/1.2A"
			(at 341.6681 132.08 0)
			(effects
				(font
					(size 1.27 1.27)
				)
			)
		)
		(property "MPN" "MPZ1005S121CT000"
			(at 330.2 123.19 0)
			(effects
				(font
					(size 1.27 1.27)
					(thickness 0.15)
				)
				(justify left bottom)
				(hide yes)
			)
		)
		(property "Manufacturer" "TDK"
			(at 330.2 120.65 0)
			(effects
				(font
					(size 1.27 1.27)
					(thickness 0.15)
				)
				(justify left bottom)
				(hide yes)
			)
		)
		(property "Current" ""
			(at 323.85 113.03 0)
			(effects
				(font
					(size 1.27 1.27)
					(thickness 0.15)
				)
				(justify left bottom)
				(hide yes)
			)
		)
		(property "Author" "Antmicro"
			(at 330.2 118.11 0)
			(effects
				(font
					(size 1.27 1.27)
					(thickness 0.15)
				)
				(justify left bottom)
				(hide yes)
			)
		)
		(property "License" "Apache-2.0"
			(at 330.2 115.57 0)
			(effects
				(font
					(size 1.27 1.27)
					(thickness 0.15)
				)
				(justify left bottom)
				(hide yes)
			)
		)
		(property "Public" ""
			(at 323.85 120.65 0)
			(effects
				(font
					(size 1.27 1.27)
				)
				(justify left bottom)
				(hide yes)
			)
		)
		(pin "1"
		)
		(pin "2"
		)
		(instances
			(project "polarfire-som"
				(path ""
					(reference "FB10")
					(unit 1)
				)
			)
		)
	)
	(symbol
		(lib_id "antmicropower:PWR_FLAG")
		(at 361.95 118.11 270)
		(unit 1)
		(exclude_from_sim no)
		(in_bom yes)
		(on_board yes)
		(dnp no)
		(property "Reference" "#FLG011"
			(at 363.855 118.11 0)
			(effects
				(font
					(size 1.27 1.27)
				)
				(hide yes)
			)
		)
		(property "Value" "PWR_FLAG"
			(at 369.57 118.11 90)
			(effects
				(font
					(size 1.27 1.27)
				)
			)
		)
		(property "Footprint" ""
			(at 361.95 118.11 0)
			(effects
				(font
					(size 1.27 1.27)
				)
				(hide yes)
			)
		)
		(property "Datasheet" ""
			(at 361.95 118.11 0)
			(effects
				(font
					(size 1.27 1.27)
				)
				(hide yes)
			)
		)
		(property "Description" ""
			(at 361.95 118.11 0)
			(effects
				(font
					(size 1.27 1.27)
				)
				(hide yes)
			)
		)
		(pin "1"
		)
		(instances
			(project "polarfire-som"
				(path ""
					(reference "#FLG011")
					(unit 1)
				)
			)
		)
	)
)
